G04 ================== begin FILE IDENTIFICATION RECORD ==================*
G04 Layout Name:  D:/<user>/Wistron_project/16315-1/gbr/16315-1.brd*
G04 Film Name:    TSMD*
G04 File Format:  Gerber RS274X*
G04 File Origin:  Cadence Allegro 16.5-S056*
G04 Origin Date:  Fri Jun 09 15:30:46 2017*
G04 *
G04 Layer:  VIA CLASS/PASTEMASK_TOP*
G04 Layer:  PIN/PASTEMASK_TOP*
G04 Layer:  PACKAGE GEOMETRY/PASTEMASK_TOP*
G04 Layer:  DRAWING FORMAT/LAYER_PCB_STORY*
G04 Layer:  DRAWING FORMAT/LAYER_PAST_T*
G04 Layer:  BOARD GEOMETRY/PANEL_OUTLINE*
G04 *
G04 Offset:    (0.00 0.00)*
G04 Mirror:    No*
G04 Mode:      Positive*
G04 Rotation:  0*
G04 FullContactRelief:  No*
G04 UndefLineWidth:     6.00*
G04 ================== end FILE IDENTIFICATION RECORD ====================*
%FSLAX35Y35*MOIN*%
%IR0*IPPOS*OFA0.00000B0.00000*MIA0B0*SFA1.00000B1.00000*%
%AMMACRO41*
4,1,40,.013,.017,
-.013,.017,
-.013695,.016939,
-.014368,.016759,
-.015,.016464,
-.015571,.016064,
-.016064,.015571,
-.016464,.015,
-.016759,.014368,
-.016939,.013695,
-.017,.013,
-.017,-.013,
-.016939,-.013695,
-.016759,-.014368,
-.016464,-.015,
-.016064,-.015571,
-.015571,-.016064,
-.015,-.016464,
-.014368,-.016759,
-.013695,-.016939,
-.013,-.017,
.013,-.017,
.013695,-.016939,
.014368,-.016759,
.015,-.016464,
.015571,-.016064,
.016064,-.015571,
.016464,-.015,
.016759,-.014368,
.016939,-.013695,
.017,-.013,
.017,.013,
.016939,.013695,
.016759,.014368,
.016464,.015,
.016064,.015571,
.015571,.016064,
.015,.016464,
.014368,.016759,
.013695,.016939,
.013,.017,
0.0*
%
%ADD41MACRO41*%
%AMMACRO14*
4,1,40,.017,-.013,
.017,.013,
.016939,.013695,
.016759,.014368,
.016464,.015,
.016064,.015571,
.015571,.016064,
.015,.016464,
.014368,.016759,
.013695,.016939,
.013,.017,
-.013,.017,
-.013695,.016939,
-.014368,.016759,
-.015,.016464,
-.015571,.016064,
-.016064,.015571,
-.016464,.015,
-.016759,.014368,
-.016939,.013695,
-.017,.013,
-.017,-.013,
-.016939,-.013695,
-.016759,-.014368,
-.016464,-.015,
-.016064,-.015571,
-.015571,-.016064,
-.015,-.016464,
-.014368,-.016759,
-.013695,-.016939,
-.013,-.017,
.013,-.017,
.013695,-.016939,
.014368,-.016759,
.015,-.016464,
.015571,-.016064,
.016064,-.015571,
.016464,-.015,
.016759,-.014368,
.016939,-.013695,
.017,-.013,
0.0*
%
%ADD14MACRO14*%
%ADD77R,.055X.11*%
%ADD68R,.056X.14*%
%ADD82R,.08X.127*%
%ADD15C,.04*%
%ADD80R,.22X.096*%
%ADD47C,.032*%
%AMMACRO44*
4,1,40,-.007,.004,
-.007,-.004,
-.00697,-.004347,
-.006879,-.004684,
-.006732,-.005,
-.006532,-.005286,
-.006286,-.005532,
-.006,-.005732,
-.005684,-.005879,
-.005347,-.00597,
-.005,-.006,
.005,-.006,
.005347,-.00597,
.005684,-.005879,
.006,-.005732,
.006286,-.005532,
.006532,-.005286,
.006732,-.005,
.006879,-.004684,
.00697,-.004347,
.007,-.004,
.007,.004,
.00697,.004347,
.006879,.004684,
.006732,.005,
.006532,.005286,
.006286,.005532,
.006,.005732,
.005684,.005879,
.005347,.00597,
.005,.006,
-.005,.006,
-.005347,.00597,
-.005684,.005879,
-.006,.005732,
-.006286,.005532,
-.006532,.005286,
-.006732,.005,
-.006879,.004684,
-.00697,.004347,
-.007,.004,
0.0*
%
%ADD44MACRO44*%
%ADD11C,.026*%
%AMMACRO62*
4,1,40,.0225,-.007,
.022378,-.008389,
.022018,-.009736,
.021428,-.011,
.020628,-.012142,
.019642,-.013128,
.0185,-.013928,
.017236,-.014518,
.015889,-.014878,
.0145,-.015,
-.0145,-.015,
-.015889,-.014878,
-.017236,-.014518,
-.0185,-.013928,
-.019642,-.013128,
-.020628,-.012142,
-.021428,-.011,
-.022018,-.009736,
-.022378,-.008389,
-.0225,-.007,
-.0225,.007,
-.022378,.008389,
-.022018,.009736,
-.021428,.011,
-.020628,.012142,
-.019642,.013128,
-.0185,.013928,
-.017236,.014518,
-.015889,.014878,
-.0145,.015,
.0145,.015,
.015889,.014878,
.017236,.014518,
.0185,.013928,
.019642,.013128,
.020628,.012142,
.021428,.011,
.022018,.009736,
.022378,.008389,
.0225,.007,
.0225,-.007,
0.0*
%
%ADD62MACRO62*%
%AMMACRO54*
4,1,46,-.00177,-.018,
-.003163,-.017918,
-.00452,-.017595,
-.0058,-.017042,
-.006965,-.016274,
-.007979,-.015316,
-.008812,-.014196,
-.009437,-.012949,
-.009836,-.011613,
-.009997,-.010227,
-.01,-.01,
-.01,.01,
-.00999,.01,
-.009868,.011389,
-.009507,.012737,
-.008918,.014001,
-.008118,.015143,
-.007132,.016129,
-.005989,.016929,
-.004725,.017519,
-.003378,.01788,
-.001989,.018001,
-.00185,.018,
.00185,.018,
.003241,.017903,
.004595,.017565,
.005869,.016998,
.007025,.016218,
.008028,.015249,
.008848,.01412,
.009459,.012867,
.009843,.011526,
.009989,.010139,
.00999,.01,
.01,.01,
.01,-.01,
.009878,-.01139,
.009517,-.012737,
.008928,-.014002,
.008128,-.015144,
.007141,-.016131,
.005998,-.016931,
.004734,-.017521,
.003387,-.017882,
.001997,-.018003,
.00177,-.018,
-.00177,-.018,
0.0*
%
%ADD54MACRO54*%
%AMMACRO10*
4,1,40,-.007,-.0225,
-.008389,-.022378,
-.009736,-.022018,
-.011,-.021428,
-.012142,-.020628,
-.013128,-.019642,
-.013928,-.0185,
-.014518,-.017236,
-.014878,-.015889,
-.015,-.0145,
-.015,.0145,
-.014878,.015889,
-.014518,.017236,
-.013928,.0185,
-.013128,.019642,
-.012142,.020628,
-.011,.021428,
-.009736,.022018,
-.008389,.022378,
-.007,.0225,
.007,.0225,
.008389,.022378,
.009736,.022018,
.011,.021428,
.012142,.020628,
.013128,.019642,
.013928,.0185,
.014518,.017236,
.014878,.015889,
.015,.0145,
.015,-.0145,
.014878,-.015889,
.014518,-.017236,
.013928,-.0185,
.013128,-.019642,
.012142,-.020628,
.011,-.021428,
.009736,-.022018,
.008389,-.022378,
.007,-.0225,
-.007,-.0225,
0.0*
%
%ADD10MACRO10*%
%AMMACRO22*
4,1,40,.007,.011,
-.007,.011,
-.007695,.010939,
-.008368,.010759,
-.009,.010464,
-.009571,.010064,
-.010064,.009571,
-.010464,.009,
-.010759,.008368,
-.010939,.007695,
-.011,.007,
-.011,-.007,
-.010939,-.007695,
-.010759,-.008368,
-.010464,-.009,
-.010064,-.009571,
-.009571,-.010064,
-.009,-.010464,
-.008368,-.010759,
-.007695,-.010939,
-.007,-.011,
.007,-.011,
.007695,-.010939,
.008368,-.010759,
.009,-.010464,
.009571,-.010064,
.010064,-.009571,
.010464,-.009,
.010759,-.008368,
.010939,-.007695,
.011,-.007,
.011,.007,
.010939,.007695,
.010759,.008368,
.010464,.009,
.010064,.009571,
.009571,.010064,
.009,.010464,
.008368,.010759,
.007695,.010939,
.007,.011,
0.0*
%
%ADD22MACRO22*%
%AMMACRO16*
4,1,40,.011,-.007,
.011,.007,
.010939,.007695,
.010759,.008368,
.010464,.009,
.010064,.009571,
.009571,.010064,
.009,.010464,
.008368,.010759,
.007695,.010939,
.007,.011,
-.007,.011,
-.007695,.010939,
-.008368,.010759,
-.009,.010464,
-.009571,.010064,
-.010064,.009571,
-.010464,.009,
-.010759,.008368,
-.010939,.007695,
-.011,.007,
-.011,-.007,
-.010939,-.007695,
-.010759,-.008368,
-.010464,-.009,
-.010064,-.009571,
-.009571,-.010064,
-.009,-.010464,
-.008368,-.010759,
-.007695,-.010939,
-.007,-.011,
.007,-.011,
.007695,-.010939,
.008368,-.010759,
.009,-.010464,
.009571,-.010064,
.010064,-.009571,
.010464,-.009,
.010759,-.008368,
.010939,-.007695,
.011,-.007,
0.0*
%
%ADD16MACRO16*%
%AMMACRO30*
4,1,40,-.012,.008,
-.012,-.008,
-.011939,-.008695,
-.011759,-.009368,
-.011464,-.01,
-.011064,-.010571,
-.010571,-.011064,
-.01,-.011464,
-.009368,-.011759,
-.008695,-.011939,
-.008,-.012,
.008,-.012,
.008695,-.011939,
.009368,-.011759,
.01,-.011464,
.010571,-.011064,
.011064,-.010571,
.011464,-.01,
.011759,-.009368,
.011939,-.008695,
.012,-.008,
.012,.008,
.011939,.008695,
.011759,.009368,
.011464,.01,
.011064,.010571,
.010571,.011064,
.01,.011464,
.009368,.011759,
.008695,.011939,
.008,.012,
-.008,.012,
-.008695,.011939,
-.009368,.011759,
-.01,.011464,
-.010571,.011064,
-.011064,.010571,
-.011464,.01,
-.011759,.009368,
-.011939,.008695,
-.012,.008,
0.0*
%
%ADD30MACRO30*%
%AMMACRO50*
4,1,40,.008,.012,
-.008,.012,
-.008695,.011939,
-.009368,.011759,
-.01,.011464,
-.010571,.011064,
-.011064,.010571,
-.011464,.01,
-.011759,.009368,
-.011939,.008695,
-.012,.008,
-.012,-.008,
-.011939,-.008695,
-.011759,-.009368,
-.011464,-.01,
-.011064,-.010571,
-.010571,-.011064,
-.01,-.011464,
-.009368,-.011759,
-.008695,-.011939,
-.008,-.012,
.008,-.012,
.008695,-.011939,
.009368,-.011759,
.01,-.011464,
.010571,-.011064,
.011064,-.010571,
.011464,-.01,
.011759,-.009368,
.011939,-.008695,
.012,-.008,
.012,.008,
.011939,.008695,
.011759,.009368,
.011464,.01,
.011064,.010571,
.010571,.011064,
.01,.011464,
.009368,.011759,
.008695,.011939,
.008,.012,
0.0*
%
%ADD50MACRO50*%
%AMMACRO46*
4,1,40,-.013,-.017,
.013,-.017,
.013695,-.016939,
.014368,-.016759,
.015,-.016464,
.015571,-.016064,
.016064,-.015571,
.016464,-.015,
.016759,-.014368,
.016939,-.013695,
.017,-.013,
.017,.013,
.016939,.013695,
.016759,.014368,
.016464,.015,
.016064,.015571,
.015571,.016064,
.015,.016464,
.014368,.016759,
.013695,.016939,
.013,.017,
-.013,.017,
-.013695,.016939,
-.014368,.016759,
-.015,.016464,
-.015571,.016064,
-.016064,.015571,
-.016464,.015,
-.016759,.014368,
-.016939,.013695,
-.017,.013,
-.017,-.013,
-.016939,-.013695,
-.016759,-.014368,
-.016464,-.015,
-.016064,-.015571,
-.015571,-.016064,
-.015,-.016464,
-.014368,-.016759,
-.013695,-.016939,
-.013,-.017,
0.0*
%
%ADD46MACRO46*%
%AMMACRO34*
4,1,40,-.017,.013,
-.017,-.013,
-.016939,-.013695,
-.016759,-.014368,
-.016464,-.015,
-.016064,-.015571,
-.015571,-.016064,
-.015,-.016464,
-.014368,-.016759,
-.013695,-.016939,
-.013,-.017,
.013,-.017,
.013695,-.016939,
.014368,-.016759,
.015,-.016464,
.015571,-.016064,
.016064,-.015571,
.016464,-.015,
.016759,-.014368,
.016939,-.013695,
.017,-.013,
.017,.013,
.016939,.013695,
.016759,.014368,
.016464,.015,
.016064,.015571,
.015571,.016064,
.015,.016464,
.014368,.016759,
.013695,.016939,
.013,.017,
-.013,.017,
-.013695,.016939,
-.014368,.016759,
-.015,.016464,
-.015571,.016064,
-.016064,.015571,
-.016464,.015,
-.016759,.014368,
-.016939,.013695,
-.017,.013,
0.0*
%
%ADD34MACRO34*%
%AMMACRO23*
4,1,40,.007,.011,
-.007,.011,
-.007695,.010939,
-.008368,.010759,
-.009,.010464,
-.009571,.010064,
-.010064,.009571,
-.010464,.009,
-.010759,.008368,
-.010939,.007695,
-.011,.007,
-.011,-.007,
-.010939,-.007695,
-.010759,-.008368,
-.010464,-.009,
-.010064,-.009571,
-.009571,-.010064,
-.009,-.010464,
-.008368,-.010759,
-.007695,-.010939,
-.007,-.011,
.007,-.011,
.007695,-.010939,
.008368,-.010759,
.009,-.010464,
.009571,-.010064,
.010064,-.009571,
.010464,-.009,
.010759,-.008368,
.010939,-.007695,
.011,-.007,
.011,.007,
.010939,.007695,
.010759,.008368,
.010464,.009,
.010064,.009571,
.009571,.010064,
.009,.010464,
.008368,.010759,
.007695,.010939,
.007,.011,
0.0*
%
%ADD23MACRO23*%
%AMMACRO17*
4,1,40,.011,-.007,
.011,.007,
.010939,.007695,
.010759,.008368,
.010464,.009,
.010064,.009571,
.009571,.010064,
.009,.010464,
.008368,.010759,
.007695,.010939,
.007,.011,
-.007,.011,
-.007695,.010939,
-.008368,.010759,
-.009,.010464,
-.009571,.010064,
-.010064,.009571,
-.010464,.009,
-.010759,.008368,
-.010939,.007695,
-.011,.007,
-.011,-.007,
-.010939,-.007695,
-.010759,-.008368,
-.010464,-.009,
-.010064,-.009571,
-.009571,-.010064,
-.009,-.010464,
-.008368,-.010759,
-.007695,-.010939,
-.007,-.011,
.007,-.011,
.007695,-.010939,
.008368,-.010759,
.009,-.010464,
.009571,-.010064,
.010064,-.009571,
.010464,-.009,
.010759,-.008368,
.010939,-.007695,
.011,-.007,
0.0*
%
%ADD17MACRO17*%
%AMMACRO31*
4,1,40,-.012,.008,
-.012,-.008,
-.011939,-.008695,
-.011759,-.009368,
-.011464,-.01,
-.011064,-.010571,
-.010571,-.011064,
-.01,-.011464,
-.009368,-.011759,
-.008695,-.011939,
-.008,-.012,
.008,-.012,
.008695,-.011939,
.009368,-.011759,
.01,-.011464,
.010571,-.011064,
.011064,-.010571,
.011464,-.01,
.011759,-.009368,
.011939,-.008695,
.012,-.008,
.012,.008,
.011939,.008695,
.011759,.009368,
.011464,.01,
.011064,.010571,
.010571,.011064,
.01,.011464,
.009368,.011759,
.008695,.011939,
.008,.012,
-.008,.012,
-.008695,.011939,
-.009368,.011759,
-.01,.011464,
-.010571,.011064,
-.011064,.010571,
-.011464,.01,
-.011759,.009368,
-.011939,.008695,
-.012,.008,
0.0*
%
%ADD31MACRO31*%
%AMMACRO51*
4,1,40,.008,.012,
-.008,.012,
-.008695,.011939,
-.009368,.011759,
-.01,.011464,
-.010571,.011064,
-.011064,.010571,
-.011464,.01,
-.011759,.009368,
-.011939,.008695,
-.012,.008,
-.012,-.008,
-.011939,-.008695,
-.011759,-.009368,
-.011464,-.01,
-.011064,-.010571,
-.010571,-.011064,
-.01,-.011464,
-.009368,-.011759,
-.008695,-.011939,
-.008,-.012,
.008,-.012,
.008695,-.011939,
.009368,-.011759,
.01,-.011464,
.010571,-.011064,
.011064,-.010571,
.011464,-.01,
.011759,-.009368,
.011939,-.008695,
.012,-.008,
.012,.008,
.011939,.008695,
.011759,.009368,
.011464,.01,
.011064,.010571,
.010571,.011064,
.01,.011464,
.009368,.011759,
.008695,.011939,
.008,.012,
0.0*
%
%ADD51MACRO51*%
%AMMACRO45*
4,1,40,-.013,-.017,
.013,-.017,
.013695,-.016939,
.014368,-.016759,
.015,-.016464,
.015571,-.016064,
.016064,-.015571,
.016464,-.015,
.016759,-.014368,
.016939,-.013695,
.017,-.013,
.017,.013,
.016939,.013695,
.016759,.014368,
.016464,.015,
.016064,.015571,
.015571,.016064,
.015,.016464,
.014368,.016759,
.013695,.016939,
.013,.017,
-.013,.017,
-.013695,.016939,
-.014368,.016759,
-.015,.016464,
-.015571,.016064,
-.016064,.015571,
-.016464,.015,
-.016759,.014368,
-.016939,.013695,
-.017,.013,
-.017,-.013,
-.016939,-.013695,
-.016759,-.014368,
-.016464,-.015,
-.016064,-.015571,
-.015571,-.016064,
-.015,-.016464,
-.014368,-.016759,
-.013695,-.016939,
-.013,-.017,
0.0*
%
%ADD45MACRO45*%
%AMMACRO35*
4,1,40,-.017,.013,
-.017,-.013,
-.016939,-.013695,
-.016759,-.014368,
-.016464,-.015,
-.016064,-.015571,
-.015571,-.016064,
-.015,-.016464,
-.014368,-.016759,
-.013695,-.016939,
-.013,-.017,
.013,-.017,
.013695,-.016939,
.014368,-.016759,
.015,-.016464,
.015571,-.016064,
.016064,-.015571,
.016464,-.015,
.016759,-.014368,
.016939,-.013695,
.017,-.013,
.017,.013,
.016939,.013695,
.016759,.014368,
.016464,.015,
.016064,.015571,
.015571,.016064,
.015,.016464,
.014368,.016759,
.013695,.016939,
.013,.017,
-.013,.017,
-.013695,.016939,
-.014368,.016759,
-.015,.016464,
-.015571,.016064,
-.016064,.015571,
-.016464,.015,
-.016759,.014368,
-.016939,.013695,
-.017,.013,
0.0*
%
%ADD35MACRO35*%
%ADD53R,.04X.022*%
%ADD78R,.02X.06*%
%ADD63R,.06X.03*%
%ADD24R,.022X.04*%
%ADD83R,.012X.06*%
%ADD79R,.03X.06*%
%ADD60R,.012X.042*%
%ADD58R,.042X.012*%
%ADD73R,.06X.014*%
%ADD52R,.04X.016*%
%ADD64R,.045X.03*%
%ADD49R,.014X.06*%
%ADD39R,.016X.04*%
%ADD86R,.03X.045*%
%ADD59R,.012X.036*%
%ADD57R,.036X.012*%
%AMMACRO84*
4,1,40,.007,-.004,
.007,.004,
.00697,.004347,
.006879,.004684,
.006732,.005,
.006532,.005286,
.006286,.005532,
.006,.005732,
.005684,.005879,
.005347,.00597,
.005,.006,
-.005,.006,
-.005347,.00597,
-.005684,.005879,
-.006,.005732,
-.006286,.005532,
-.006532,.005286,
-.006732,.005,
-.006879,.004684,
-.00697,.004347,
-.007,.004,
-.007,-.004,
-.00697,-.004347,
-.006879,-.004684,
-.006732,-.005,
-.006532,-.005286,
-.006286,-.005532,
-.006,-.005732,
-.005684,-.005879,
-.005347,-.00597,
-.005,-.006,
.005,-.006,
.005347,-.00597,
.005684,-.005879,
.006,-.005732,
.006286,-.005532,
.006532,-.005286,
.006732,-.005,
.006879,-.004684,
.00697,-.004347,
.007,-.004,
0.0*
%
%ADD84MACRO84*%
%ADD72R,.016X.06*%
%ADD37R,.093X.02*%
%ADD76R,.02X.093*%
%ADD27R,.05X.065*%
%ADD40R,.065X.05*%
%ADD85R,.065X.025*%
%ADD65R,.045X.09*%
%ADD38R,.093X.024*%
%ADD32R,.028X.034*%
%ADD87R,.09X.045*%
%ADD74R,.024X.093*%
%ADD48R,.048X.016*%
%ADD36R,.102X.102*%
%ADD29R,.025X.065*%
%ADD28R,.045X.055*%
%ADD75R,.016X.048*%
%ADD61R,.13X.13*%
%ADD43R,.055X.045*%
%ADD70R,.047X.073*%
%ADD67R,.024X.059*%
%ADD71R,.073X.047*%
%AMMACRO89*
4,1,46,.00177,.018,
.003163,.017918,
.00452,.017595,
.0058,.017042,
.006965,.016274,
.007979,.015316,
.008812,.014196,
.009437,.012949,
.009836,.011613,
.009997,.010227,
.01,.01,
.01,-.01,
.00999,-.01,
.009868,-.011389,
.009507,-.012737,
.008918,-.014001,
.008118,-.015143,
.007132,-.016129,
.005989,-.016929,
.004725,-.017519,
.003378,-.01788,
.001989,-.018001,
.00185,-.018,
-.00185,-.018,
-.003241,-.017903,
-.004595,-.017565,
-.005869,-.016998,
-.007025,-.016218,
-.008028,-.015249,
-.008848,-.01412,
-.009459,-.012867,
-.009843,-.011526,
-.009989,-.010139,
-.00999,-.01,
-.01,-.01,
-.01,.01,
-.009878,.01139,
-.009517,.012737,
-.008928,.014002,
-.008128,.015144,
-.007141,.016131,
-.005998,.016931,
-.004734,.017521,
-.003387,.017882,
-.001997,.018003,
-.00177,.018,
.00177,.018,
0.0*
%
%ADD89MACRO89*%
%ADD81R,.035X.096*%
%ADD69R,.09X.095*%
%AMMACRO88*
4,1,40,-.0225,.007,
-.022378,.008389,
-.022018,.009736,
-.021428,.011,
-.020628,.012142,
-.019642,.013128,
-.0185,.013928,
-.017236,.014518,
-.015889,.014878,
-.0145,.015,
.0145,.015,
.015889,.014878,
.017236,.014518,
.0185,.013928,
.019642,.013128,
.020628,.012142,
.021428,.011,
.022018,.009736,
.022378,.008389,
.0225,.007,
.0225,-.007,
.022378,-.008389,
.022018,-.009736,
.021428,-.011,
.020628,-.012142,
.019642,-.013128,
.0185,-.013928,
.017236,-.014518,
.015889,-.014878,
.0145,-.015,
-.0145,-.015,
-.015889,-.014878,
-.017236,-.014518,
-.0185,-.013928,
-.019642,-.013128,
-.020628,-.012142,
-.021428,-.011,
-.022018,-.009736,
-.022378,-.008389,
-.0225,-.007,
-.0225,.007,
0.0*
%
%ADD88MACRO88*%
%AMMACRO33*
4,1,40,.007,.0225,
.008389,.022378,
.009736,.022018,
.011,.021428,
.012142,.020628,
.013128,.019642,
.013928,.0185,
.014518,.017236,
.014878,.015889,
.015,.0145,
.015,-.0145,
.014878,-.015889,
.014518,-.017236,
.013928,-.0185,
.013128,-.019642,
.012142,-.020628,
.011,-.021428,
.009736,-.022018,
.008389,-.022378,
.007,-.0225,
-.007,-.0225,
-.008389,-.022378,
-.009736,-.022018,
-.011,-.021428,
-.012142,-.020628,
-.013128,-.019642,
-.013928,-.0185,
-.014518,-.017236,
-.014878,-.015889,
-.015,-.0145,
-.015,.0145,
-.014878,.015889,
-.014518,.017236,
-.013928,.0185,
-.013128,.019642,
-.012142,.020628,
-.011,.021428,
-.009736,.022018,
-.008389,.022378,
-.007,.0225,
.007,.0225,
0.0*
%
%ADD33MACRO33*%
%ADD66R,.059X.079*%
%AMMACRO56*
4,1,40,-.008,-.012,
.008,-.012,
.008695,-.011939,
.009368,-.011759,
.01,-.011464,
.010571,-.011064,
.011064,-.010571,
.011464,-.01,
.011759,-.009368,
.011939,-.008695,
.012,-.008,
.012,.008,
.011939,.008695,
.011759,.009368,
.011464,.01,
.011064,.010571,
.010571,.011064,
.01,.011464,
.009368,.011759,
.008695,.011939,
.008,.012,
-.008,.012,
-.008695,.011939,
-.009368,.011759,
-.01,.011464,
-.010571,.011064,
-.011064,.010571,
-.011464,.01,
-.011759,.009368,
-.011939,.008695,
-.012,.008,
-.012,-.008,
-.011939,-.008695,
-.011759,-.009368,
-.011464,-.01,
-.011064,-.010571,
-.010571,-.011064,
-.01,-.011464,
-.009368,-.011759,
-.008695,-.011939,
-.008,-.012,
0.0*
%
%ADD56MACRO56*%
%AMMACRO25*
4,1,40,.012,-.008,
.012,.008,
.011939,.008695,
.011759,.009368,
.011464,.01,
.011064,.010571,
.010571,.011064,
.01,.011464,
.009368,.011759,
.008695,.011939,
.008,.012,
-.008,.012,
-.008695,.011939,
-.009368,.011759,
-.01,.011464,
-.010571,.011064,
-.011064,.010571,
-.011464,.01,
-.011759,.009368,
-.011939,.008695,
-.012,.008,
-.012,-.008,
-.011939,-.008695,
-.011759,-.009368,
-.011464,-.01,
-.011064,-.010571,
-.010571,-.011064,
-.01,-.011464,
-.009368,-.011759,
-.008695,-.011939,
-.008,-.012,
.008,-.012,
.008695,-.011939,
.009368,-.011759,
.01,-.011464,
.010571,-.011064,
.011064,-.010571,
.011464,-.01,
.011759,-.009368,
.011939,-.008695,
.012,-.008,
0.0*
%
%ADD25MACRO25*%
%AMMACRO20*
4,1,40,-.007,-.011,
.007,-.011,
.007695,-.010939,
.008368,-.010759,
.009,-.010464,
.009571,-.010064,
.010064,-.009571,
.010464,-.009,
.010759,-.008368,
.010939,-.007695,
.011,-.007,
.011,.007,
.010939,.007695,
.010759,.008368,
.010464,.009,
.010064,.009571,
.009571,.010064,
.009,.010464,
.008368,.010759,
.007695,.010939,
.007,.011,
-.007,.011,
-.007695,.010939,
-.008368,.010759,
-.009,.010464,
-.009571,.010064,
-.010064,.009571,
-.010464,.009,
-.010759,.008368,
-.010939,.007695,
-.011,.007,
-.011,-.007,
-.010939,-.007695,
-.010759,-.008368,
-.010464,-.009,
-.010064,-.009571,
-.009571,-.010064,
-.009,-.010464,
-.008368,-.010759,
-.007695,-.010939,
-.007,-.011,
0.0*
%
%ADD20MACRO20*%
%AMMACRO18*
4,1,40,-.011,.007,
-.011,-.007,
-.010939,-.007695,
-.010759,-.008368,
-.010464,-.009,
-.010064,-.009571,
-.009571,-.010064,
-.009,-.010464,
-.008368,-.010759,
-.007695,-.010939,
-.007,-.011,
.007,-.011,
.007695,-.010939,
.008368,-.010759,
.009,-.010464,
.009571,-.010064,
.010064,-.009571,
.010464,-.009,
.010759,-.008368,
.010939,-.007695,
.011,-.007,
.011,.007,
.010939,.007695,
.010759,.008368,
.010464,.009,
.010064,.009571,
.009571,.010064,
.009,.010464,
.008368,.010759,
.007695,.010939,
.007,.011,
-.007,.011,
-.007695,.010939,
-.008368,.010759,
-.009,.010464,
-.009571,.010064,
-.010064,.009571,
-.010464,.009,
-.010759,.008368,
-.010939,.007695,
-.011,.007,
0.0*
%
%ADD18MACRO18*%
%AMMACRO42*
4,1,40,.013,.017,
-.013,.017,
-.013695,.016939,
-.014368,.016759,
-.015,.016464,
-.015571,.016064,
-.016064,.015571,
-.016464,.015,
-.016759,.014368,
-.016939,.013695,
-.017,.013,
-.017,-.013,
-.016939,-.013695,
-.016759,-.014368,
-.016464,-.015,
-.016064,-.015571,
-.015571,-.016064,
-.015,-.016464,
-.014368,-.016759,
-.013695,-.016939,
-.013,-.017,
.013,-.017,
.013695,-.016939,
.014368,-.016759,
.015,-.016464,
.015571,-.016064,
.016064,-.015571,
.016464,-.015,
.016759,-.014368,
.016939,-.013695,
.017,-.013,
.017,.013,
.016939,.013695,
.016759,.014368,
.016464,.015,
.016064,.015571,
.015571,.016064,
.015,.016464,
.014368,.016759,
.013695,.016939,
.013,.017,
0.0*
%
%ADD42MACRO42*%
%AMMACRO13*
4,1,40,.017,-.013,
.017,.013,
.016939,.013695,
.016759,.014368,
.016464,.015,
.016064,.015571,
.015571,.016064,
.015,.016464,
.014368,.016759,
.013695,.016939,
.013,.017,
-.013,.017,
-.013695,.016939,
-.014368,.016759,
-.015,.016464,
-.015571,.016064,
-.016064,.015571,
-.016464,.015,
-.016759,.014368,
-.016939,.013695,
-.017,.013,
-.017,-.013,
-.016939,-.013695,
-.016759,-.014368,
-.016464,-.015,
-.016064,-.015571,
-.015571,-.016064,
-.015,-.016464,
-.014368,-.016759,
-.013695,-.016939,
-.013,-.017,
.013,-.017,
.013695,-.016939,
.014368,-.016759,
.015,-.016464,
.015571,-.016064,
.016064,-.015571,
.016464,-.015,
.016759,-.014368,
.016939,-.013695,
.017,-.013,
0.0*
%
%ADD13MACRO13*%
%AMMACRO55*
4,1,40,-.008,-.012,
.008,-.012,
.008695,-.011939,
.009368,-.011759,
.01,-.011464,
.010571,-.011064,
.011064,-.010571,
.011464,-.01,
.011759,-.009368,
.011939,-.008695,
.012,-.008,
.012,.008,
.011939,.008695,
.011759,.009368,
.011464,.01,
.011064,.010571,
.010571,.011064,
.01,.011464,
.009368,.011759,
.008695,.011939,
.008,.012,
-.008,.012,
-.008695,.011939,
-.009368,.011759,
-.01,.011464,
-.010571,.011064,
-.011064,.010571,
-.011464,.01,
-.011759,.009368,
-.011939,.008695,
-.012,.008,
-.012,-.008,
-.011939,-.008695,
-.011759,-.009368,
-.011464,-.01,
-.011064,-.010571,
-.010571,-.011064,
-.01,-.011464,
-.009368,-.011759,
-.008695,-.011939,
-.008,-.012,
0.0*
%
%ADD55MACRO55*%
%AMMACRO26*
4,1,40,.012,-.008,
.012,.008,
.011939,.008695,
.011759,.009368,
.011464,.01,
.011064,.010571,
.010571,.011064,
.01,.011464,
.009368,.011759,
.008695,.011939,
.008,.012,
-.008,.012,
-.008695,.011939,
-.009368,.011759,
-.01,.011464,
-.010571,.011064,
-.011064,.010571,
-.011464,.01,
-.011759,.009368,
-.011939,.008695,
-.012,.008,
-.012,-.008,
-.011939,-.008695,
-.011759,-.009368,
-.011464,-.01,
-.011064,-.010571,
-.010571,-.011064,
-.01,-.011464,
-.009368,-.011759,
-.008695,-.011939,
-.008,-.012,
.008,-.012,
.008695,-.011939,
.009368,-.011759,
.01,-.011464,
.010571,-.011064,
.011064,-.010571,
.011464,-.01,
.011759,-.009368,
.011939,-.008695,
.012,-.008,
0.0*
%
%ADD26MACRO26*%
%AMMACRO21*
4,1,40,-.007,-.011,
.007,-.011,
.007695,-.010939,
.008368,-.010759,
.009,-.010464,
.009571,-.010064,
.010064,-.009571,
.010464,-.009,
.010759,-.008368,
.010939,-.007695,
.011,-.007,
.011,.007,
.010939,.007695,
.010759,.008368,
.010464,.009,
.010064,.009571,
.009571,.010064,
.009,.010464,
.008368,.010759,
.007695,.010939,
.007,.011,
-.007,.011,
-.007695,.010939,
-.008368,.010759,
-.009,.010464,
-.009571,.010064,
-.010064,.009571,
-.010464,.009,
-.010759,.008368,
-.010939,.007695,
-.011,.007,
-.011,-.007,
-.010939,-.007695,
-.010759,-.008368,
-.010464,-.009,
-.010064,-.009571,
-.009571,-.010064,
-.009,-.010464,
-.008368,-.010759,
-.007695,-.010939,
-.007,-.011,
0.0*
%
%ADD21MACRO21*%
%AMMACRO19*
4,1,40,-.011,.007,
-.011,-.007,
-.010939,-.007695,
-.010759,-.008368,
-.010464,-.009,
-.010064,-.009571,
-.009571,-.010064,
-.009,-.010464,
-.008368,-.010759,
-.007695,-.010939,
-.007,-.011,
.007,-.011,
.007695,-.010939,
.008368,-.010759,
.009,-.010464,
.009571,-.010064,
.010064,-.009571,
.010464,-.009,
.010759,-.008368,
.010939,-.007695,
.011,-.007,
.011,.007,
.010939,.007695,
.010759,.008368,
.010464,.009,
.010064,.009571,
.009571,.010064,
.009,.010464,
.008368,.010759,
.007695,.010939,
.007,.011,
-.007,.011,
-.007695,.010939,
-.008368,.010759,
-.009,.010464,
-.009571,.010064,
-.010064,.009571,
-.010464,.009,
-.010759,.008368,
-.010939,.007695,
-.011,.007,
0.0*
%
%ADD19MACRO19*%
%ADD90C,.02*%
%ADD91C,.006*%
G75*
%LPD*%
G75*
G36*
G01X653392Y594286D02*
Y585286D01*
X661992D01*
Y594286D01*
X653392D01*
G37*
G36*
G01Y606086D02*
Y597086D01*
X661992D01*
Y606086D01*
X653392D01*
G37*
G36*
G01X664792D02*
Y597086D01*
X673392D01*
Y606086D01*
X664792D01*
G37*
G36*
G01Y594286D02*
Y585286D01*
X673392D01*
Y594286D01*
X664792D01*
G37*
G36*
G01X1038955Y1487511D02*
X1047955D01*
Y1496111D01*
X1038955D01*
Y1487511D01*
G37*
G36*
G01X1027155D02*
X1036155D01*
Y1496111D01*
X1027155D01*
Y1487511D01*
G37*
G36*
G01Y1498911D02*
X1036155D01*
Y1507511D01*
X1027155D01*
Y1498911D01*
G37*
G36*
G01X1038955D02*
X1047955D01*
Y1507511D01*
X1038955D01*
Y1498911D01*
G37*
G36*
G01X1011155Y1487511D02*
X1020155D01*
Y1496111D01*
X1011155D01*
Y1487511D01*
G37*
G36*
G01X999355D02*
X1008355D01*
Y1496111D01*
X999355D01*
Y1487511D01*
G37*
G36*
G01Y1498911D02*
X1008355D01*
Y1507511D01*
X999355D01*
Y1498911D01*
G37*
G36*
G01X1011155D02*
X1020155D01*
Y1507511D01*
X1011155D01*
Y1498911D01*
G37*
G36*
G01X1066755Y1487511D02*
X1075755D01*
Y1496111D01*
X1066755D01*
Y1487511D01*
G37*
G36*
G01X1054955D02*
X1063955D01*
Y1496111D01*
X1054955D01*
Y1487511D01*
G37*
G36*
G01Y1498911D02*
X1063955D01*
Y1507511D01*
X1054955D01*
Y1498911D01*
G37*
G36*
G01X1066755D02*
X1075755D01*
Y1507511D01*
X1066755D01*
Y1498911D01*
G37*
G36*
G01X1373300Y545900D02*
X1382300D01*
Y554500D01*
X1373300D01*
Y545900D01*
G37*
G36*
G01Y557300D02*
X1382300D01*
Y565900D01*
X1373300D01*
Y557300D01*
G37*
G36*
G01X1385100Y545900D02*
X1394100D01*
Y554500D01*
X1385100D01*
Y545900D01*
G37*
G36*
G01Y557300D02*
X1394100D01*
Y565900D01*
X1385100D01*
Y557300D01*
G37*
G54D10*
X22947Y674933D03*
X23314Y700284D03*
X22920Y1127900D03*
X22894Y1153251D03*
X26822Y682433D03*
X30697Y674933D03*
X27189Y707784D03*
X31064Y700284D03*
X30670Y1127900D03*
X26795Y1135400D03*
X26769Y1160751D03*
X30644Y1153251D03*
X149826Y732591D03*
X145951Y725091D03*
X153701D03*
X145955Y740011D03*
X153705D03*
X149830Y747511D03*
X149841Y1177842D03*
X145966Y1170342D03*
X153716D03*
X150001Y1200224D03*
X146126Y1192724D03*
X153876D03*
X274093Y732335D03*
X270218Y724835D03*
X277968D03*
X270222Y739755D03*
X277972D03*
X274097Y747255D03*
X274055Y1177842D03*
X270180Y1170342D03*
X277930D03*
X274215Y1200224D03*
X270340Y1192724D03*
X278090D03*
X398250Y732263D03*
X394375Y724763D03*
X402125D03*
X394379Y739683D03*
X402129D03*
X398254Y747183D03*
X398281Y1179045D03*
X394406Y1171545D03*
X402156D03*
X398386Y1200224D03*
X394511Y1192724D03*
X402261D03*
X522346Y732516D03*
X518471Y725016D03*
X526221D03*
X518475Y739936D03*
X526225D03*
X522350Y747436D03*
X522648Y1180116D03*
X518773Y1172616D03*
X526523D03*
X522513Y1200182D03*
X518638Y1192682D03*
X526388D03*
X646780Y732433D03*
X642905Y724933D03*
X650655D03*
X642909Y739853D03*
X650659D03*
X646784Y747353D03*
X646864Y1179909D03*
X642989Y1172409D03*
X650739D03*
X646769Y1200140D03*
X642894Y1192640D03*
X650644D03*
X934960Y949195D03*
X931085Y941695D03*
X938835D03*
X1225845Y1160891D03*
X1221970Y1153391D03*
X1229720D03*
X1239945Y1160864D03*
X1236070Y1153364D03*
X1243820D03*
X1357711Y1131655D03*
X1365461D03*
X1361586Y1139155D03*
X1360794Y1160724D03*
X1356919Y1153224D03*
X1364669D03*
X1481346Y1126841D03*
X1489096D03*
X1485221Y1134341D03*
X1485468Y1160808D03*
X1481593Y1153308D03*
X1489343D03*
X1620052Y1114449D03*
X1619446Y1138567D03*
X1623927Y1121949D03*
X1627802Y1114449D03*
X1623321Y1146067D03*
X1627196Y1138567D03*
X1728978Y1127935D03*
X1736728D03*
X1732853Y1135435D03*
X1732996Y1160608D03*
X1729121Y1153108D03*
X1736871D03*
X1860667Y1153308D03*
X1850477Y1160786D03*
X1846602Y1153286D03*
X1854352D03*
X1864542Y1160808D03*
X1868417Y1153308D03*
G54D20*
X67937Y205261D03*
X60037Y179561D03*
Y632317D03*
X67937Y657917D03*
X30993Y692869D03*
X30626Y667518D03*
X67937Y1110673D03*
X59937Y1085073D03*
X30206Y1120485D03*
X30573Y1145836D03*
X92237Y191161D03*
X88596Y629631D03*
X92237Y643917D03*
X120395Y999067D03*
X92237Y1096673D03*
X153703Y714355D03*
X154312Y1158233D03*
X153882Y1186220D03*
X184149Y179661D03*
X192149Y204961D03*
X216449Y191161D03*
X187095Y587067D03*
X216449Y633417D03*
X188599Y621417D03*
X204502Y620496D03*
X191849Y1106373D03*
X216449Y1096673D03*
X184427Y1094839D03*
X184439Y1099043D03*
X308362Y179661D03*
X308462Y632417D03*
X277970Y714099D03*
X308362Y1085173D03*
X278526Y1158233D03*
X278096Y1186220D03*
X319155Y68379D03*
X329479Y68345D03*
X316362Y205061D03*
X340662Y191161D03*
X337132Y629429D03*
X340662Y644017D03*
X316362Y657717D03*
Y1110573D03*
X340762Y1096773D03*
X402127Y714027D03*
X402353Y1185011D03*
X432674Y179661D03*
X440574Y205061D03*
X432674Y632317D03*
X440674Y657817D03*
X453373Y1104326D03*
X464874Y191161D03*
X461303Y629682D03*
X464874Y643917D03*
X508174Y1110573D03*
X556787Y179561D03*
X526223Y714280D03*
X526451Y1163084D03*
X526317Y1186666D03*
X589087Y191161D03*
X564887Y204861D03*
X592479Y566331D03*
X589087Y643917D03*
X556887Y632317D03*
X564887Y657717D03*
X564787Y1110473D03*
X589087Y1096673D03*
X556887Y1085173D03*
X616958Y538745D03*
Y542745D03*
X650657Y714197D03*
X651166Y1160810D03*
X650576Y1186007D03*
X694257Y107247D03*
X689000Y205161D03*
X681000Y179561D03*
X685450Y631917D03*
X701353Y630996D03*
X689000Y657917D03*
X688700Y1106273D03*
X680600Y1093100D03*
X713300Y191161D03*
Y643917D03*
Y1096673D03*
X885200Y41500D03*
X878257Y378495D03*
X882973Y816103D03*
X874523Y814580D03*
X881073Y856903D03*
X936981Y912047D03*
X936713Y1028083D03*
X936624Y1032390D03*
X961700Y1552700D03*
X1022568Y-40100D03*
X1014100Y58900D03*
Y63600D03*
Y54200D03*
X1014872Y545207D03*
X1014806Y554532D03*
X1034214Y872741D03*
X1032929Y1324216D03*
X1038053Y1349992D03*
X1032929Y1337616D03*
X1033029Y1342668D03*
X1032929Y1330916D03*
X1065571Y-80978D03*
X1042258Y-75936D03*
X1069618Y22405D03*
X1044173Y835703D03*
X1042073Y872703D03*
X1104300Y-78400D03*
X1113321Y-80838D03*
X1104379Y-86862D03*
X1089268Y-87500D03*
X1089250Y-60300D03*
X1180402Y96794D03*
X1180249Y101360D03*
X1183000Y249800D03*
X1190832D03*
X1229647Y1145325D03*
X1256700Y244861D03*
X1243764Y1145413D03*
X1314021Y90855D03*
Y86155D03*
X1345703Y133842D03*
X1332700Y194661D03*
X1363928Y542311D03*
X1332700Y647417D03*
Y1100173D03*
X1365354Y1123365D03*
X1364663Y1147073D03*
X1417769Y520457D03*
Y527857D03*
X1425400Y549600D03*
Y553600D03*
X1378913Y697517D03*
Y1150273D03*
X1456913Y194661D03*
X1451900Y526100D03*
X1459900D03*
X1432400Y540100D03*
X1456913Y647417D03*
Y1100173D03*
X1503225Y244661D03*
X1486800Y525900D03*
X1483800Y530900D03*
X1485800Y560400D03*
Y556100D03*
X1503125Y697517D03*
X1489058Y1117943D03*
X1503125Y1150373D03*
X1489283Y1144062D03*
X1581125Y194661D03*
X1576125Y649417D03*
X1590225Y1093873D03*
X1628938Y244661D03*
X1627338Y697517D03*
X1627513Y1128071D03*
X1627748Y1106754D03*
X1639138Y1150273D03*
X1705338Y194661D03*
Y647417D03*
Y1100173D03*
X1753750Y244661D03*
X1762195Y1011067D03*
X1736695Y1120127D03*
X1751550Y1150273D03*
X1736891Y1145478D03*
X1829550Y194661D03*
X1859669Y204961D03*
X1851717Y194075D03*
X1829550Y647417D03*
X1851717Y646831D03*
X1859669Y657817D03*
X1829550Y1100173D03*
X1859791Y1098787D03*
X1851696Y1098813D03*
G54D11*
X21999Y667471D03*
X22600Y693100D03*
X21626Y1120900D03*
X22100Y1146200D03*
X25000Y1209100D03*
X60187Y194161D03*
X67987Y199261D03*
X68937Y262161D03*
X72049Y424200D03*
X68109Y453300D03*
X43100Y464100D03*
X57963Y457439D03*
X47607Y520462D03*
X61834Y520466D03*
X60187Y646917D03*
X67987Y651900D03*
X68937Y714917D03*
X33900Y764200D03*
X28400Y763600D03*
X72049Y923100D03*
X68109Y932900D03*
X60187Y1099673D03*
X68100Y1104973D03*
X68937Y1167673D03*
X30000Y1206100D03*
X52600Y1201300D03*
X48219Y1196721D03*
X77237Y181411D03*
X81437Y177911D03*
X88300Y186300D03*
X82437Y260661D03*
X79200Y233800D03*
X77237Y634167D03*
X81437Y630667D03*
X87819Y638950D03*
X85146Y625491D03*
X79000Y686500D03*
X82437Y713417D03*
X108647Y980933D03*
X96563Y969225D03*
X110363Y1003825D03*
X117063Y1006725D03*
X108063Y988125D03*
X102113Y998225D03*
X81437Y1083423D03*
X77237Y1086923D03*
X88787Y1091673D03*
X82437Y1166173D03*
X78700Y1139500D03*
X139187Y250161D03*
X145437Y261100D03*
X167992Y400500D03*
X168813Y586225D03*
X163263Y557225D03*
X139187Y702917D03*
X150253Y718842D03*
X140364Y745281D03*
X145437Y713700D03*
X159600Y758942D03*
X149830Y762815D03*
X132175Y979825D03*
X133663Y973825D03*
X131563Y966735D03*
X128063Y1006725D03*
X150869Y1163222D03*
X139187Y1155673D03*
X140166Y1214922D03*
X147538Y1213917D03*
X144264Y1186512D03*
X165490Y1217508D03*
X154473Y1213919D03*
X201449Y181411D03*
X184399Y194161D03*
X192199Y199061D03*
X205649Y177911D03*
X212999Y186161D03*
X206649Y260661D03*
X203400Y234000D03*
X193149Y262161D03*
X196261Y397500D03*
X192321Y406000D03*
X182217Y399500D03*
X171861Y520420D03*
X186088Y520424D03*
X210263Y550725D03*
X177063Y591825D03*
X194763Y594725D03*
X183763D03*
X174763Y576125D03*
X198263Y554735D03*
X198004Y567809D03*
X200363Y561825D03*
X202174Y625523D03*
X196360Y638400D03*
X207409Y625539D03*
X212999Y628417D03*
X203600Y686800D03*
X198000Y650000D03*
X206649Y713417D03*
X193149Y714917D03*
X202534Y917700D03*
X206200Y925200D03*
X208700Y1023450D03*
X205649Y1083423D03*
X201449Y1086923D03*
X183793Y1104177D03*
X194100Y1101800D03*
X212999Y1091673D03*
X206649Y1166173D03*
X193149Y1167673D03*
X203100Y1139500D03*
X263399Y250161D03*
X232400Y569725D03*
X263399Y702917D03*
X264731Y745025D03*
X263399Y1155673D03*
X311000Y76700D03*
X308612Y194161D03*
X269649Y260800D03*
X292153Y491834D03*
X306388Y491797D03*
X296032Y520420D03*
X310259Y520424D03*
X308612Y646917D03*
X268071Y713929D03*
X274520Y718586D03*
X283516Y768434D03*
X274097Y762119D03*
X308612Y1099673D03*
X275087Y1163231D03*
X268478Y1186512D03*
X284954Y1257055D03*
X280888Y1249308D03*
X303376Y1248708D03*
X306015Y1256575D03*
X353894Y66695D03*
X335766Y74334D03*
X322965Y77565D03*
X329529Y77300D03*
X329961Y115700D03*
X333741Y117531D03*
X319329Y117277D03*
X340201Y118481D03*
X325662Y181411D03*
X316412Y199161D03*
X329862Y177911D03*
X337212Y186161D03*
X330862Y260661D03*
X327600Y234000D03*
X317362Y262161D03*
X320925Y491367D03*
X315925Y491578D03*
X325662Y634167D03*
X329862Y630667D03*
X336409Y639049D03*
X333682Y625711D03*
X328000Y686700D03*
X316412Y651917D03*
X330862Y713417D03*
X317362Y714917D03*
X320925Y943284D03*
X315925Y943495D03*
X329862Y1083423D03*
X325662Y1086923D03*
X317811Y1102937D03*
X337312Y1091773D03*
X330862Y1166173D03*
X317362Y1167673D03*
X327600Y1139400D03*
X371619Y84720D03*
X370390Y95920D03*
X387612Y251061D03*
X391986Y262414D03*
X387612Y702917D03*
X393862Y714500D03*
X398677Y718514D03*
X388788Y744953D03*
X407714Y756056D03*
X398254Y757066D03*
X387612Y1155673D03*
X393698Y1166123D03*
X393193Y1220531D03*
X391827Y1214891D03*
X392977Y1185945D03*
X403487Y1213549D03*
X449874Y181411D03*
X432824Y194161D03*
X440624Y199100D03*
X454074Y177911D03*
X455074Y260661D03*
X451800Y234000D03*
X441574Y262161D03*
X445138Y492299D03*
X440138Y492173D03*
X416303Y491797D03*
X430538Y491760D03*
X420182Y520383D03*
X434409Y520387D03*
X449874Y634167D03*
X432824Y646917D03*
X454074Y630667D03*
X457853Y625956D03*
X452000Y686600D03*
X441600Y650800D03*
X455074Y713417D03*
X441574Y714917D03*
X445138Y943284D03*
X440138Y943495D03*
X443923Y1082726D03*
X452173Y1075476D03*
X447423Y1086926D03*
X453423Y1108600D03*
X456174Y1167573D03*
X415430Y1216989D03*
X461424Y186161D03*
X460521Y638901D03*
X511824Y250161D03*
X518074Y260500D03*
X539350Y491729D03*
X534350Y491940D03*
X510621Y491834D03*
X524856Y491797D03*
X550161Y544768D03*
X549279Y524831D03*
X554889Y550331D03*
X521191Y545078D03*
X514500Y520420D03*
X528727Y520424D03*
X553279Y530931D03*
Y537910D03*
X536900Y528500D03*
X536891Y532831D03*
X554055Y576466D03*
X552379Y566531D03*
X536979Y553219D03*
X513729Y557675D03*
X511824Y702917D03*
X515025Y715075D03*
X522773Y718767D03*
X512884Y745206D03*
X531810Y755383D03*
X522350Y756393D03*
X509300Y1121500D03*
X514000Y1139900D03*
X514274Y1161673D03*
X518975Y1167110D03*
X517342Y1185651D03*
X544486Y1266486D03*
X534733Y1252634D03*
X547100Y1232500D03*
X554772Y1250785D03*
X574087Y181411D03*
X557037Y194161D03*
X566160Y197579D03*
X578287Y177911D03*
X585637Y186161D03*
X579287Y260661D03*
X576700Y234000D03*
X565787Y262161D03*
X575607Y499947D03*
X588026Y526957D03*
X594795Y504965D03*
X569347Y524499D03*
X587279Y547831D03*
X575779Y524831D03*
X588978Y534615D03*
X564388Y526640D03*
X599247Y525694D03*
X596414Y538329D03*
Y543329D03*
X560500Y558600D03*
X601979Y559456D03*
X593779Y556274D03*
X576029Y561181D03*
X568029Y560831D03*
X586279Y560331D03*
X562279Y565331D03*
X580053Y559080D03*
X574087Y634167D03*
X557037Y646917D03*
X578287Y630667D03*
X585637Y638917D03*
X576300Y686800D03*
X564937Y651917D03*
X579287Y713417D03*
X565787Y714917D03*
X569350Y945784D03*
X564350Y945995D03*
X578287Y1083423D03*
X574087Y1086923D03*
X557037Y1099673D03*
X564837Y1104800D03*
X585637Y1091673D03*
X579000Y1166500D03*
X565787Y1167673D03*
X576000Y1139700D03*
X616903Y107633D03*
X636037Y250161D03*
X642287Y262200D03*
X627863Y517621D03*
X642344Y516870D03*
X606884Y525791D03*
X642152Y578952D03*
X636037Y702917D03*
X642287Y714800D03*
X647207Y718684D03*
X637318Y745123D03*
X646784Y756310D03*
X636037Y1155673D03*
X647716Y1165672D03*
X638776Y1214234D03*
X641383Y1186238D03*
X661638Y109969D03*
X685711Y101931D03*
X698300Y181411D03*
X681250Y194161D03*
X690166Y198044D03*
X699900Y233700D03*
X690000Y262161D03*
X693112Y382100D03*
X689172Y380276D03*
X693112Y361401D03*
X689172Y362876D03*
X699025Y636023D03*
X679213Y612355D03*
X690213Y603973D03*
X701000Y686700D03*
X689758Y649790D03*
X689050Y669146D03*
X690000Y714917D03*
X656244Y755300D03*
X689172Y928400D03*
X693112Y940100D03*
X698300Y1086923D03*
X680400Y1105800D03*
X691400Y1101900D03*
X690000Y1167673D03*
X700100Y1139500D03*
X658241Y1228338D03*
X658303Y1216330D03*
X679907Y1232607D03*
X702500Y177911D03*
X709850Y186161D03*
X703500Y260661D03*
X704260Y635957D03*
X709850Y638917D03*
X703500Y713417D03*
X702500Y1083423D03*
X709850Y1091673D03*
X703500Y1166173D03*
X758000Y223500D03*
X760250Y1154000D03*
X882900Y359100D03*
X883200Y378495D03*
X882400Y445462D03*
X882500Y450200D03*
Y454900D03*
X870179D03*
X870389Y445462D03*
X870221Y450200D03*
X882600Y459562D03*
X882700Y464505D03*
X870263Y459562D03*
X883900Y542405D03*
X884182Y820251D03*
X879519Y821655D03*
X874623Y822631D03*
X881203Y852900D03*
X876900D03*
X885873Y852800D03*
X888643Y1356566D03*
X889223Y1350339D03*
X885754Y1375500D03*
X885608Y1379698D03*
X877500Y1443500D03*
X881901Y1443300D03*
X871325Y1443125D03*
X888000Y1478800D03*
X883647Y1478447D03*
X879341Y1478200D03*
X882572Y1492349D03*
X879321Y1489661D03*
X855535Y1498705D03*
X855523Y1504750D03*
X888390Y1534018D03*
X855899Y1529934D03*
X867500Y1519500D03*
X915654Y916254D03*
X921100Y916100D03*
X928100Y916200D03*
X923600Y905000D03*
X928100Y905300D03*
X901540Y916200D03*
X904100Y912860D03*
X933524Y916449D03*
X923985Y954185D03*
X918577Y955523D03*
X929960Y954810D03*
X918220Y985720D03*
X923100Y985700D03*
X927460Y985574D03*
X927917Y974344D03*
X934343Y978450D03*
X912994Y967848D03*
X910594Y955106D03*
X906600Y985800D03*
X908094Y965295D03*
X905506Y958415D03*
X902866Y964401D03*
X900400Y960942D03*
X901480Y985800D03*
X926513Y1023713D03*
X920500Y1024400D03*
X932316Y1023966D03*
X942893Y1001345D03*
X918430Y1040930D03*
X919778Y1047278D03*
X919400Y1056000D03*
X914100Y1056200D03*
X910387Y1051177D03*
X904875Y1046590D03*
X924200Y1371800D03*
X924436Y1367064D03*
X924400Y1362000D03*
X925313Y1356403D03*
X924300Y1376100D03*
X938000Y1511000D03*
X918500Y1510200D03*
X898378Y1478800D03*
X924000Y1518200D03*
X929000Y1544700D03*
X921500Y1544200D03*
X924300Y1530184D03*
X937250Y1547200D03*
X924110Y1536700D03*
X931500Y1548200D03*
X923400Y1524279D03*
X900248Y1521048D03*
X904900Y1534500D03*
X958200Y915800D03*
X963066Y915830D03*
X953320Y915800D03*
X961100Y949800D03*
X956800Y949900D03*
X950400Y949800D03*
X951700Y986600D03*
X956300D03*
X947400Y986458D03*
X981580Y953300D03*
X979020Y949700D03*
X976460Y953300D03*
X973900Y949800D03*
X971340Y953300D03*
X968780Y949800D03*
X944617Y975530D03*
X945790Y945819D03*
X956100Y1020300D03*
X951800D03*
X946800Y1020200D03*
X981500Y1179000D03*
X968800Y1158500D03*
X957346Y1516124D03*
X964419Y1509261D03*
X946300Y1511200D03*
X967998Y1512551D03*
X988573Y1513673D03*
X971069Y1495465D03*
X972158Y1542266D03*
X961008Y1546961D03*
X959987Y1541339D03*
X945250Y1547450D03*
X956597Y1533926D03*
X955236Y1546187D03*
X958199Y1520984D03*
X948750Y1545050D03*
X998045Y-90000D03*
X1006660Y-81200D03*
X1010800Y-77400D03*
X1004100Y-47369D03*
X1029900Y-75400D03*
X1004100Y-65700D03*
X1039560Y-45900D03*
X1038808Y-67700D03*
X1019100Y-43996D03*
Y-62000D03*
X1010380Y-20480D03*
X1011125Y-15559D03*
X1005981Y58902D03*
X1004000Y54400D03*
X1005400Y63780D03*
X1006815Y545207D03*
X1006400Y554532D03*
X1035958Y838664D03*
X1037400Y868600D03*
X1033600Y912400D03*
X1019221Y913481D03*
X1025400Y912800D03*
X1012750Y926499D03*
X1000174Y986100D03*
X1006694D03*
X1023100Y951000D03*
X994900Y986000D03*
X1009200Y1020500D03*
X1003000Y1023000D03*
X998439Y1023100D03*
X1029339Y1077911D03*
X1034069Y1077881D03*
X1024500Y1077800D03*
X1031400Y1112664D03*
X1026900Y1114107D03*
X1022400Y1114181D03*
X1026900Y1125640D03*
X1022400Y1125311D03*
X998208Y1148628D03*
X1004500Y1148300D03*
X1011497Y1148303D03*
X1009500Y1180377D03*
X1014500Y1180413D03*
X1004500Y1180370D03*
X1038000Y1324216D03*
X1038200Y1337616D03*
X1038400Y1342668D03*
X1038200Y1330916D03*
X1018483Y1474093D03*
X1075100Y-86200D03*
X1049500Y-73200D03*
X1062073Y-51100D03*
X1062400Y-72800D03*
X1074400Y-50694D03*
Y-69174D03*
X1073400Y22405D03*
X1073598Y79465D03*
X1053774Y429753D03*
X1053721Y434409D03*
X1047853Y446600D03*
X1053700Y557053D03*
X1049301Y835703D03*
X1046937Y829163D03*
X1042123Y868400D03*
X1083633Y864110D03*
X1046803Y868900D03*
X1042155Y912845D03*
X1051573Y912477D03*
X1083633Y902332D03*
X1074292Y1077704D03*
X1078534Y1077715D03*
X1069870Y1077770D03*
X1086842Y1114342D03*
X1079000Y1115489D03*
X1074500Y1115393D03*
X1041975Y1349992D03*
X1042039Y1354526D03*
X1074283Y1474093D03*
X1046283D03*
X1070400Y1521000D03*
X1105400Y-91100D03*
X1112600Y-94000D03*
X1089300Y-82962D03*
X1094300Y-84700D03*
X1089300Y-64555D03*
X1111778Y-60293D03*
X1107362Y-59500D03*
X1096500Y-53500D03*
X1120179Y1078250D03*
X1125362Y1078488D03*
X1115520Y1078475D03*
X1127100Y1113738D03*
X1122500Y1113770D03*
X1118000D03*
X1136007Y1114387D03*
X1172375Y101360D03*
X1171552Y96794D03*
X1185100Y245100D03*
X1185588Y301468D03*
X1180953Y303520D03*
X1176272Y301668D03*
X1180953Y288600D03*
X1185588Y288981D03*
X1182411Y317764D03*
X1178081Y329765D03*
X1148997Y1097672D03*
X1148830Y1091117D03*
X1145936Y1113107D03*
X1142020Y1114701D03*
X1138679Y1117874D03*
X1176500Y1127000D03*
X1223600Y241100D03*
X1190882Y255782D03*
X1190200Y301168D03*
X1220200Y268800D03*
X1190200Y288892D03*
X1192600Y277700D03*
X1188900Y281300D03*
X1192600Y273400D03*
X1189924Y314076D03*
X1188400Y1029031D03*
X1189900Y1033731D03*
X1211205Y1174705D03*
X1220723Y1146560D03*
X1216205Y1182451D03*
X1256500Y250161D03*
X1249000Y227700D03*
X1250500Y262600D03*
X1261500Y451500D03*
X1256500Y465200D03*
X1239758Y489880D03*
X1250660Y478500D03*
X1244910Y513555D03*
X1259426Y513463D03*
X1254500Y702917D03*
X1250660Y714960D03*
X1268742Y922198D03*
X1263742Y938298D03*
X1240222Y911913D03*
X1254331Y935742D03*
X1245251Y965973D03*
X1259600Y965700D03*
X1254750Y1155423D03*
X1251053Y1168353D03*
X1234995Y1146053D03*
X1242718Y1190900D03*
X1238778Y1222200D03*
X1304563Y96258D03*
X1323181Y89965D03*
X1328161Y90500D03*
X1299569Y96258D03*
X1317900Y90500D03*
X1327307Y124489D03*
X1319807Y125683D03*
X1317445Y120920D03*
X1317000Y178161D03*
X1308250Y186200D03*
X1324500Y194661D03*
X1317000Y169411D03*
X1326300Y165911D03*
X1310500Y247161D03*
X1310501Y279736D03*
X1317000Y630917D03*
X1302500Y642417D03*
X1324500Y647417D03*
X1317000Y622167D03*
X1326423Y618667D03*
X1310882Y732348D03*
X1310500Y699917D03*
X1317000Y1083673D03*
X1313400Y1074923D03*
X1302500Y1095173D03*
X1324500Y1100173D03*
X1310500Y1152673D03*
X1310494Y1184880D03*
X1336516Y87410D03*
X1337176Y78470D03*
X1340961Y82656D03*
X1343521Y89403D03*
X1348641Y87218D03*
X1331759Y80400D03*
X1333281Y90526D03*
X1349931Y134433D03*
X1331365Y125601D03*
X1351008Y124582D03*
X1343170Y125197D03*
X1336500Y194661D03*
X1334534Y274847D03*
X1374713Y263900D03*
X1366931Y402900D03*
X1362991Y429900D03*
X1347982Y482100D03*
X1356542Y458900D03*
X1341262Y513426D03*
X1355778Y513334D03*
X1368165Y542402D03*
X1361500Y567500D03*
X1369300Y578700D03*
X1336500Y647417D03*
X1378713Y702917D03*
X1334385Y726575D03*
X1374839Y715539D03*
X1362991Y888400D03*
X1366931Y921200D03*
X1345800Y924700D03*
X1354301Y935405D03*
X1343677Y965649D03*
X1358581Y966602D03*
X1336500Y1100173D03*
X1356639Y1123408D03*
X1378963Y1155600D03*
X1375887Y1169387D03*
X1355100Y1147400D03*
X1334232Y1181463D03*
X1346321Y1182700D03*
X1351321Y1211900D03*
X1366931Y1198700D03*
X1362991Y1254400D03*
X1380713Y251400D03*
X1402872Y535918D03*
X1426713Y642417D03*
Y1095173D03*
X1441213Y178161D03*
X1460713Y194661D03*
X1432463Y186623D03*
X1448713Y194661D03*
X1441213Y169411D03*
X1450700Y165937D03*
X1434713Y247161D03*
X1434890Y279853D03*
X1458098Y274316D03*
X1472194Y448500D03*
X1463085Y494974D03*
X1462848Y512169D03*
X1467000Y533700D03*
X1475600Y525900D03*
X1440400Y537300D03*
X1432800Y535300D03*
X1452584Y530090D03*
X1459950Y531600D03*
X1440700Y544600D03*
X1441700Y532100D03*
X1473090Y542100D03*
X1465700Y527100D03*
X1449614Y533651D03*
X1430431Y549130D03*
X1444000Y567000D03*
X1434414Y580369D03*
X1459200Y568200D03*
X1452200Y567600D03*
X1439000Y558000D03*
X1463521Y567421D03*
X1474700Y561500D03*
Y554521D03*
X1433200Y571600D03*
X1428200Y562850D03*
X1430431Y554130D03*
X1451686Y594814D03*
X1441213Y630917D03*
X1460713Y647417D03*
X1448713D03*
X1441213Y622167D03*
X1451016Y618667D03*
X1435496Y732268D03*
X1458283Y728459D03*
X1434713Y699917D03*
X1466036Y937510D03*
X1467889Y965707D03*
X1441213Y1083673D03*
Y1074923D03*
X1446213Y1066700D03*
X1460713Y1100173D03*
X1448713D03*
X1458334Y1180299D03*
X1434713Y1152673D03*
X1434536Y1185247D03*
X1503025Y250061D03*
X1497025Y273400D03*
X1491143Y420100D03*
X1487203Y448300D03*
X1481938Y493921D03*
X1477766Y479986D03*
X1477818Y547663D03*
X1492700Y539112D03*
X1512940Y533903D03*
X1478700Y567600D03*
X1502925Y702917D03*
X1498349Y715749D03*
X1491143Y863600D03*
X1487203Y887900D03*
X1484054Y911900D03*
X1482793Y966760D03*
X1479828Y1118016D03*
X1504700Y1156926D03*
X1500838Y1167938D03*
X1480600Y1144400D03*
X1491143Y1211600D03*
X1476175Y1265600D03*
X1481175Y1251700D03*
X1487203Y1234300D03*
X1565425Y178161D03*
X1556675Y186000D03*
X1565425Y169411D03*
X1558925Y247161D03*
X1559257Y279526D03*
X1565425Y630917D03*
X1551675Y640424D03*
X1565425Y622167D03*
X1567925Y649417D03*
X1559129Y732414D03*
X1558925Y699917D03*
X1565425Y1083673D03*
Y1074923D03*
X1570425Y1067600D03*
X1549425Y1092973D03*
X1558925Y1152673D03*
X1558141Y1185570D03*
X1565173Y1185730D03*
X1589100Y146241D03*
X1585757Y121382D03*
X1584925Y194661D03*
X1572925D03*
X1575479Y165911D03*
X1582965Y274048D03*
X1615356Y487800D03*
X1611416Y465200D03*
X1596407Y472700D03*
X1601101Y464367D03*
X1592144Y513510D03*
X1606660Y513418D03*
X1575057Y618667D03*
X1578976Y670497D03*
X1582690Y727290D03*
X1615356Y885149D03*
X1611416Y877400D03*
X1592128Y938753D03*
X1604967Y905900D03*
X1592102Y965633D03*
X1606800Y965889D03*
X1594025Y1093873D03*
X1582025D03*
X1619308Y1107701D03*
X1605083Y1217917D03*
X1615900Y1200200D03*
X1619940Y1225400D03*
X1615356Y1256600D03*
X1628738Y250061D03*
X1622738Y260500D03*
X1627138Y702917D03*
X1621138Y714900D03*
X1623034Y1132351D03*
X1689638Y178161D03*
X1709138Y194661D03*
X1680888Y186300D03*
X1697138Y194661D03*
X1689638Y169411D03*
X1699692Y165911D03*
X1683138Y247161D03*
X1682961Y280030D03*
X1706641Y275966D03*
X1716609Y513257D03*
X1689638Y630917D03*
X1709138Y647417D03*
X1675138Y642417D03*
X1697138Y647417D03*
X1689638Y622167D03*
X1699788Y618667D03*
X1683708Y732526D03*
X1706680Y727755D03*
X1683138Y699917D03*
X1689638Y1083673D03*
Y1074923D03*
X1694638Y1067600D03*
X1709138Y1100173D03*
X1675138Y1095173D03*
X1697138Y1100173D03*
X1683138Y1152673D03*
X1682961Y1185542D03*
X1706935Y1180888D03*
X1753550Y250061D03*
X1747550Y261100D03*
X1729179Y393700D03*
X1739568Y453500D03*
X1723619Y436700D03*
X1735628Y476630D03*
X1731125Y513165D03*
X1755459Y711160D03*
X1739568Y852900D03*
X1735628Y883800D03*
X1752000Y901047D03*
X1749145Y918827D03*
X1749242Y970095D03*
X1764356Y970161D03*
X1749573Y939015D03*
X1738363Y981225D03*
X1752163Y1015825D03*
X1758863Y1018725D03*
X1749863Y1000125D03*
X1743913Y1010225D03*
X1727481Y1120480D03*
X1751600Y1155523D03*
X1746700Y1169200D03*
X1727463Y1145781D03*
X1739568Y1209300D03*
X1735628Y1226800D03*
X1718117Y1274820D03*
X1723117Y1266400D03*
X1813850Y178161D03*
X1804897Y187050D03*
X1813850Y169411D03*
X1807350Y247161D03*
X1807880Y279499D03*
X1813850Y630917D03*
X1799350Y642417D03*
X1813850Y622167D03*
X1808526Y731698D03*
X1807350Y699917D03*
X1777666Y932748D03*
X1782666Y939436D03*
X1794767Y964624D03*
X1811581Y965390D03*
X1783778Y974371D03*
X1775863Y978735D03*
X1775963Y985825D03*
X1792236Y942480D03*
X1806452Y942675D03*
X1769863Y1018725D03*
X1774000Y991825D03*
X1813850Y1083673D03*
X1810250Y1074723D03*
X1799350Y1095173D03*
X1807350Y1152673D03*
X1807527Y1185306D03*
X1841021Y156822D03*
X1845667Y176775D03*
X1833350Y194661D03*
X1851919Y199644D03*
X1859117Y193744D03*
X1821350Y194661D03*
X1842167Y172575D03*
X1850517Y165225D03*
X1823904Y165911D03*
X1831323Y274905D03*
X1860669Y262161D03*
X1859841Y452000D03*
X1844832Y446400D03*
X1853392Y476500D03*
X1840000Y513000D03*
X1854800Y513100D03*
X1845667Y629531D03*
X1833350Y647417D03*
X1859117Y646500D03*
X1821350Y647417D03*
X1842167Y625331D03*
X1850417Y617981D03*
X1823543Y618667D03*
X1840891Y610086D03*
X1851667Y652500D03*
X1847500Y659100D03*
X1821900Y676400D03*
X1830850Y730417D03*
X1854028Y713674D03*
X1814600Y983125D03*
X1857100Y1086300D03*
X1833350Y1100173D03*
X1851981Y1103613D03*
X1859974Y1109049D03*
X1821350Y1100173D03*
X1844432Y1099891D03*
X1831089Y1181419D03*
X1844138Y1240750D03*
X1845845Y1234445D03*
X1860457Y1229857D03*
X1856642Y1233142D03*
X1874400Y190744D03*
X1864775Y182057D03*
X1871200Y234100D03*
Y262000D03*
X1863781Y429200D03*
X1874500Y643500D03*
X1864000Y638000D03*
X1871000Y686600D03*
X1870198Y713498D03*
X1867652Y865421D03*
X1876555Y1070799D03*
X1872967Y1067014D03*
X1877045Y1138812D03*
X1871802Y1182620D03*
G36*
G01X44296Y882702D02*
G03Y882652I-12800J-25D01*
G01X39896D01*
G02Y882702I-8400J25D01*
G01X44296D01*
G37*
G36*
G01X181107Y646482D02*
G03Y646432I-12800J-25D01*
G01X176707D01*
G02Y646482I-8400J25D01*
G01X181107D01*
G37*
G36*
G01X673036D02*
G03Y646432I-12800J-25D01*
G01X668636D01*
G02Y646482I-8400J25D01*
G01X673036D01*
G37*
G36*
G01X730910Y820891D02*
G03Y820841I-12800J-25D01*
G01X726510D01*
G02Y820891I-8400J25D01*
G01X730910D01*
G37*
G36*
G01X1378942Y646482D02*
G03Y646432I-12800J-25D01*
G01X1374542D01*
G02Y646482I-8400J25D01*
G01X1378942D01*
G37*
G36*
G01X1475792Y866954D02*
G03Y866904I-12800J-25D01*
G01X1471392D01*
G02Y866954I-8400J25D01*
G01X1475792D01*
G37*
G36*
G01X1615556Y646482D02*
G03Y646432I-12800J-25D01*
G01X1611156D01*
G02Y646482I-8400J25D01*
G01X1615556D01*
G37*
G36*
G01X1916146Y803962D02*
G03Y803912I-12800J-25D01*
G01X1911746D01*
G02Y803962I-8400J25D01*
G01X1916146D01*
G37*
G54D21*
X64537Y205261D03*
X56637Y179561D03*
Y632317D03*
X64537Y657917D03*
X27593Y692869D03*
X27226Y667518D03*
X64537Y1110673D03*
X56537Y1085073D03*
X26806Y1120485D03*
X27173Y1145836D03*
X88837Y191161D03*
X85196Y629631D03*
X88837Y643917D03*
X116995Y999067D03*
X88837Y1096673D03*
X150303Y714355D03*
X150912Y1158233D03*
X150482Y1186220D03*
X180749Y179661D03*
X188749Y204961D03*
X213049Y191161D03*
X183695Y587067D03*
X213049Y633417D03*
X185199Y621417D03*
X201102Y620496D03*
X188449Y1106373D03*
X213049Y1096673D03*
X181027Y1094839D03*
X181039Y1099043D03*
X304962Y179661D03*
X312962Y205061D03*
X305062Y632417D03*
X312962Y657717D03*
X274570Y714099D03*
X312962Y1110573D03*
X304962Y1085173D03*
X275126Y1158233D03*
X274696Y1186220D03*
X315755Y68379D03*
X326079Y68345D03*
X337262Y191161D03*
X333732Y629429D03*
X337262Y644017D03*
X337362Y1096773D03*
X398727Y714027D03*
X398953Y1185011D03*
X429274Y179661D03*
X437174Y205061D03*
X457903Y629682D03*
X429274Y632317D03*
X437274Y657817D03*
X449973Y1104326D03*
X461474Y191161D03*
Y643917D03*
X504774Y1110573D03*
X553387Y179561D03*
X553487Y632317D03*
X522823Y714280D03*
X553487Y1085173D03*
X523051Y1163084D03*
X522917Y1186666D03*
X585687Y191161D03*
X561487Y204861D03*
X589079Y566331D03*
X585687Y643917D03*
X561487Y657717D03*
X561387Y1110473D03*
X585687Y1096673D03*
X613558Y538745D03*
Y542745D03*
X647257Y714197D03*
X647766Y1160810D03*
X647176Y1186007D03*
X690857Y107247D03*
X685600Y205161D03*
X677600Y179561D03*
X682050Y631917D03*
X697953Y630996D03*
X685600Y657917D03*
X685300Y1106273D03*
X677200Y1093100D03*
X709900Y191161D03*
Y643917D03*
Y1096673D03*
X881800Y41500D03*
X874857Y378495D03*
X879573Y816103D03*
X871123Y814580D03*
X877673Y856903D03*
X933581Y912047D03*
X933313Y1028083D03*
X933224Y1032390D03*
X958300Y1552700D03*
X1019168Y-40100D03*
X1038858Y-75936D03*
X1010700Y58900D03*
Y63600D03*
Y54200D03*
X1011472Y545207D03*
X1011406Y554532D03*
X1030814Y872741D03*
X1038673Y872703D03*
X1029529Y1324216D03*
X1034653Y1349992D03*
X1029529Y1337616D03*
X1029629Y1342668D03*
X1029529Y1330916D03*
X1085868Y-87500D03*
X1062171Y-80978D03*
X1085850Y-60300D03*
X1066218Y22405D03*
X1040773Y835703D03*
X1100900Y-78400D03*
X1109921Y-80838D03*
X1100979Y-86862D03*
X1177002Y96794D03*
X1176849Y101360D03*
X1179600Y249800D03*
X1187432D03*
X1226247Y1145325D03*
X1253300Y244861D03*
X1240364Y1145413D03*
X1310621Y90855D03*
Y86155D03*
X1329300Y194661D03*
Y647417D03*
Y1100173D03*
X1342303Y133842D03*
X1360528Y542311D03*
X1375513Y697517D03*
X1361954Y1123365D03*
X1375513Y1150273D03*
X1361263Y1147073D03*
X1414369Y520457D03*
Y527857D03*
X1422000Y549600D03*
Y553600D03*
X1453513Y194661D03*
X1448500Y526100D03*
X1456500D03*
X1429000Y540100D03*
X1453513Y647417D03*
Y1100173D03*
X1499825Y244661D03*
X1483400Y525900D03*
X1480400Y530900D03*
X1482400Y560400D03*
Y556100D03*
X1499725Y697517D03*
X1485658Y1117943D03*
X1499725Y1150373D03*
X1485883Y1144062D03*
X1577725Y194661D03*
X1572725Y649417D03*
X1586825Y1093873D03*
X1625538Y244661D03*
X1623938Y697517D03*
X1624113Y1128071D03*
X1624348Y1106754D03*
X1635738Y1150273D03*
X1701938Y194661D03*
Y647417D03*
Y1100173D03*
X1750350Y244661D03*
X1758795Y1011067D03*
X1733295Y1120127D03*
X1748150Y1150273D03*
X1733491Y1145478D03*
X1826150Y194661D03*
X1856269Y204961D03*
X1848317Y194075D03*
X1826150Y647417D03*
X1848317Y646831D03*
X1856269Y657817D03*
X1826150Y1100173D03*
X1856391Y1098787D03*
X1848296Y1098813D03*
G54D30*
X60237Y214661D03*
Y667417D03*
Y1120173D03*
X142737Y240661D03*
Y693417D03*
X142056Y971762D03*
X142737Y1146173D03*
X184449Y214661D03*
X208756Y559762D03*
X206300Y644000D03*
X190199Y671689D03*
X190249Y1123673D03*
X308662Y214661D03*
X266949Y240661D03*
X308662Y667417D03*
X266949Y693417D03*
X308662Y1120173D03*
X266949Y1146173D03*
X342529Y58745D03*
X391162Y240661D03*
Y693417D03*
Y1146173D03*
X432874Y214661D03*
Y667417D03*
X453474Y1117073D03*
X503374Y1141973D03*
X515374Y240661D03*
Y693417D03*
X557087Y214661D03*
X601901Y530600D03*
X557087Y667417D03*
Y1120173D03*
X639587Y240661D03*
Y693417D03*
Y1146173D03*
X694117Y112738D03*
X681300Y214661D03*
X681800Y669917D03*
X687100Y1124073D03*
X753000Y209600D03*
X751800Y681800D03*
X851404Y1538590D03*
X935378Y995820D03*
X914846Y1530405D03*
X971122Y1516969D03*
X1034512Y-70708D03*
X1057833Y-76247D03*
X1086507Y1561743D03*
X1110888Y-55662D03*
X1311800Y195261D03*
Y648017D03*
Y1100773D03*
X1335300Y227761D03*
Y680517D03*
Y1133273D03*
X1436013Y195261D03*
X1459513Y227761D03*
X1436013Y648017D03*
X1459513Y680517D03*
X1436013Y1100773D03*
X1459513Y1133273D03*
X1560225Y195261D03*
X1555225Y650017D03*
X1552625Y1136373D03*
X1583725Y227761D03*
Y680517D03*
X1684438Y195261D03*
X1707938Y227761D03*
X1684438Y648017D03*
X1707938Y680517D03*
X1684438Y1100773D03*
X1707938Y1133273D03*
X1763300Y716500D03*
X1808650Y195261D03*
Y648017D03*
X1783856Y983762D03*
X1808650Y1100773D03*
X1851969Y214661D03*
X1832150Y227761D03*
X1851969Y667417D03*
X1832150Y680517D03*
X1858506Y1117394D03*
X1831750Y1133173D03*
X1884885Y1064038D03*
G54D13*
X25000Y1200800D03*
X30000D03*
X95437Y295961D03*
Y748717D03*
Y1201473D03*
X135422Y1201337D03*
X140422D03*
X219649Y295961D03*
Y748717D03*
X259594Y1201168D03*
X264594D03*
X219649Y1201473D03*
X343862Y295961D03*
Y748717D03*
Y1201473D03*
X383849Y1201042D03*
X388849D03*
X468074Y295961D03*
Y748717D03*
X508103Y1200957D03*
X468074Y1201473D03*
X513103Y1200957D03*
X592287Y295961D03*
X584279Y572631D03*
X592287Y748717D03*
Y1201473D03*
X607460Y566574D03*
X632316Y1200874D03*
X637316D03*
X716500Y295961D03*
Y748717D03*
Y1201473D03*
X751209Y165428D03*
X752500Y1163300D03*
X881256Y1370750D03*
X933524Y927700D03*
X967813Y1559566D03*
X953500Y1559000D03*
X1211205Y1161994D03*
X1216205D03*
X1298500Y295461D03*
Y265961D03*
Y718717D03*
Y748217D03*
Y1171473D03*
Y1200973D03*
X1351321Y1161953D03*
X1346321D03*
X1422713Y295461D03*
Y265961D03*
X1426419Y532557D03*
X1422713Y718717D03*
Y748217D03*
Y1171473D03*
Y1200973D03*
X1470953Y1161827D03*
X1475953D03*
X1507037Y533703D03*
X1546925Y295461D03*
Y265961D03*
Y718717D03*
Y748217D03*
Y1171473D03*
Y1200973D03*
X1615552Y1162006D03*
X1620236D03*
X1671138Y295461D03*
Y265961D03*
Y718717D03*
Y748217D03*
Y1171473D03*
Y1200973D03*
X1760500Y730800D03*
X1723117Y1161953D03*
X1718117D03*
X1795350Y295461D03*
Y265961D03*
Y718717D03*
X1795468Y748394D03*
X1795350Y1171473D03*
Y1200973D03*
X1836400Y1161500D03*
X1841084Y1161521D03*
X1887169Y295961D03*
Y748717D03*
Y1201473D03*
G54D40*
X93437Y239661D03*
Y250661D03*
Y692417D03*
Y703417D03*
Y1156173D03*
Y1145173D03*
X217649Y239661D03*
Y250661D03*
Y692417D03*
Y703417D03*
Y1156173D03*
Y1145173D03*
X341862Y239661D03*
Y250661D03*
Y692417D03*
Y703417D03*
Y1156173D03*
Y1145173D03*
X466074Y239661D03*
Y250661D03*
Y692417D03*
Y703417D03*
X515774Y1156173D03*
Y1145173D03*
X590287Y239661D03*
Y250661D03*
Y692417D03*
Y703417D03*
Y1156173D03*
Y1145173D03*
X714500Y239661D03*
Y250661D03*
Y692417D03*
Y703417D03*
Y1156173D03*
Y1145173D03*
X1308500Y253661D03*
Y264661D03*
Y717417D03*
Y706417D03*
Y1170173D03*
Y1159173D03*
X1432713Y253661D03*
Y264661D03*
Y717417D03*
Y706417D03*
Y1170173D03*
Y1159173D03*
X1556925Y253661D03*
Y264661D03*
Y717417D03*
Y706417D03*
Y1170173D03*
Y1159173D03*
X1681138Y253661D03*
Y264661D03*
Y717417D03*
Y706417D03*
Y1170173D03*
Y1159173D03*
X1805350Y253661D03*
Y264661D03*
Y717417D03*
Y706417D03*
Y1170173D03*
Y1159173D03*
X1885169Y250661D03*
Y239661D03*
Y692417D03*
Y703417D03*
X1885553Y1131673D03*
Y1142673D03*
G54D31*
X56637Y214661D03*
Y667417D03*
Y1120173D03*
X139137Y240661D03*
Y693417D03*
X138456Y971762D03*
X139137Y1146173D03*
X180849Y214661D03*
X205156Y559762D03*
X202700Y644000D03*
X186599Y671689D03*
X186649Y1123673D03*
X263349Y240661D03*
Y693417D03*
Y1146173D03*
X305062Y214661D03*
Y667417D03*
Y1120173D03*
X338929Y58745D03*
X387562Y240661D03*
Y693417D03*
Y1146173D03*
X429274Y214661D03*
Y667417D03*
X449874Y1117073D03*
X499774Y1141973D03*
X511774Y240661D03*
X553487Y214661D03*
Y667417D03*
X511774Y693417D03*
X553487Y1120173D03*
X598301Y530600D03*
X635987Y240661D03*
Y693417D03*
Y1146173D03*
X690517Y112738D03*
X677700Y214661D03*
X678200Y669917D03*
X683500Y1124073D03*
X749400Y209600D03*
X748200Y681800D03*
X847804Y1538590D03*
X931778Y995820D03*
X911246Y1530405D03*
X967522Y1516969D03*
X1030912Y-70708D03*
X1054233Y-76247D03*
X1082907Y1561743D03*
X1107288Y-55662D03*
X1308200Y195261D03*
Y648017D03*
Y1100773D03*
X1331700Y227761D03*
Y680517D03*
Y1133273D03*
X1432413Y195261D03*
X1455913Y227761D03*
X1432413Y648017D03*
X1455913Y680517D03*
X1432413Y1100773D03*
X1455913Y1133273D03*
X1556625Y195261D03*
X1551625Y650017D03*
X1549025Y1136373D03*
X1580125Y227761D03*
Y680517D03*
X1680838Y195261D03*
X1704338Y227761D03*
X1680838Y648017D03*
X1704338Y680517D03*
X1680838Y1100773D03*
X1704338Y1133273D03*
X1759700Y716500D03*
X1805050Y195261D03*
Y648017D03*
X1780256Y983762D03*
X1805050Y1100773D03*
X1848369Y214661D03*
X1828550Y227761D03*
X1848369Y667417D03*
X1828550Y680517D03*
X1854906Y1117394D03*
X1828150Y1133173D03*
X1881285Y1064038D03*
G54D22*
X56737Y210561D03*
X58384Y513020D03*
X44157Y513016D03*
X56737Y663317D03*
Y1116073D03*
X88737Y176661D03*
Y181161D03*
Y633917D03*
X100863Y985725D03*
X116997Y995001D03*
X102163Y1003325D03*
X88837Y1082173D03*
Y1086673D03*
X139237Y244761D03*
X168411Y512874D03*
X168863Y591025D03*
X167563Y573725D03*
X139237Y697517D03*
X137163Y1005625D03*
X125363Y1001725D03*
X137122Y997250D03*
X124455Y992723D03*
X139237Y1150273D03*
X180949Y210561D03*
X213049Y181361D03*
Y176661D03*
X182638Y512878D03*
X203863Y593625D03*
X192063Y589725D03*
X203822Y585250D03*
X183697Y583001D03*
X191155Y580723D03*
X213049Y623417D03*
Y618917D03*
X202800Y650000D03*
X186699Y667589D03*
X213049Y1082173D03*
Y1086873D03*
X186749Y1119573D03*
X263449Y244761D03*
Y697517D03*
Y1150273D03*
X305162Y210561D03*
X306809Y512878D03*
X292582Y512874D03*
X305162Y663317D03*
Y1116073D03*
X315721Y72855D03*
X326079Y72845D03*
X337362Y176461D03*
X337262Y181161D03*
Y634017D03*
X337362Y1082073D03*
Y1086773D03*
X387662Y244761D03*
Y697517D03*
Y1150273D03*
X429374Y210561D03*
X430959Y512841D03*
X416732Y512837D03*
X429374Y663317D03*
X449974Y1112973D03*
X443973Y1091326D03*
X461474Y176461D03*
Y181161D03*
Y633917D03*
X499874Y1145973D03*
X553587Y210661D03*
X511874Y244661D03*
X541679Y528531D03*
Y532831D03*
X525277Y512878D03*
X511050Y512874D03*
X544179Y566531D03*
Y561531D03*
X553587Y663417D03*
X511874Y697417D03*
X553587Y1116173D03*
X585687Y176661D03*
Y181361D03*
X601579Y538831D03*
Y542831D03*
X576079Y566331D03*
X568079D03*
X595579Y552331D03*
X585687Y634017D03*
Y629417D03*
Y1082173D03*
Y1086873D03*
X621697Y107633D03*
X611701Y112329D03*
X636087Y244761D03*
X638684Y512541D03*
X624457Y512537D03*
X616110Y562574D03*
Y555174D03*
X636087Y697517D03*
Y1150273D03*
X677800Y210561D03*
X678300Y665817D03*
X683600Y1119973D03*
X709900Y176461D03*
Y181161D03*
X749500Y205500D03*
X709900Y633917D03*
Y629417D03*
X748300Y677700D03*
X709900Y1081973D03*
Y1086673D03*
X839000Y1538800D03*
X874850Y359100D03*
X874654Y445462D03*
X874700Y450200D03*
Y454900D03*
X874800Y471100D03*
X874754Y459562D03*
X874743Y464505D03*
X875943Y542405D03*
X885903Y856727D03*
X868672Y1358528D03*
X877912Y1380412D03*
X877911Y1375746D03*
X868508Y1523720D03*
X906900Y1512600D03*
Y1508100D03*
X937300Y1552700D03*
X916300Y1539200D03*
X913300Y1544200D03*
X968690Y1153500D03*
X945300Y1552700D03*
X976513Y1553466D03*
Y1549366D03*
X964832Y1538282D03*
X967800Y1529200D03*
Y1525200D03*
X1038858Y-71536D03*
X1015632Y-66200D03*
X1004132Y-43500D03*
X1011450Y550000D03*
X1025235Y908603D03*
X1025200Y904200D03*
X1009800Y930500D03*
X1034674Y1354526D03*
X1062121Y-76578D03*
X1062904Y79465D03*
X1046300Y442000D03*
X1046337Y429753D03*
X1046301Y434409D03*
X1046515Y557053D03*
X1109900Y-89600D03*
X1109921Y-85538D03*
X1100879Y-82462D03*
X1221510Y236291D03*
X1194650Y284750D03*
X1194429Y1033731D03*
Y1029031D03*
X1250061Y513463D03*
X1235924Y513432D03*
X1254800Y697850D03*
X1250525Y966004D03*
X1236376Y965973D03*
X1254800Y1150173D03*
X1308300Y191161D03*
Y643917D03*
Y1096673D03*
X1331800Y223661D03*
X1346413Y513334D03*
X1332276Y513303D03*
X1331800Y676417D03*
X1348846Y965705D03*
X1334805Y965825D03*
X1331800Y1129173D03*
X1381009Y244829D03*
X1432513Y191161D03*
X1456013Y223661D03*
X1435500Y526100D03*
X1432513Y643917D03*
X1456013Y676417D03*
X1473058Y965763D03*
X1459017Y965883D03*
X1456013Y1129173D03*
X1432513Y1096673D03*
X1556725Y191161D03*
X1551725Y645917D03*
X1549125Y1132273D03*
X1580225Y223661D03*
X1597295Y513418D03*
X1583158Y513387D03*
X1580225Y676417D03*
X1597371Y965889D03*
X1583230Y965809D03*
X1680938Y191161D03*
X1704438Y223661D03*
X1707623Y513134D03*
X1680938Y643917D03*
X1704438Y676417D03*
X1680938Y1096673D03*
X1704438Y1129173D03*
X1721760Y513165D03*
X1759800Y720500D03*
X1759934Y965756D03*
X1745736Y965664D03*
X1758797Y1007001D03*
X1743963Y1015325D03*
X1742663Y997725D03*
X1805150Y191161D03*
Y643917D03*
X1802627Y965626D03*
X1790438Y968689D03*
X1767163Y1013725D03*
X1778922Y1009250D03*
X1766255Y1004723D03*
X1778963Y1017625D03*
X1805150Y1096673D03*
X1848469Y210461D03*
X1842117Y181175D03*
X1828650Y223661D03*
X1845595Y513292D03*
X1831458Y513261D03*
X1842217Y633931D03*
X1828650Y676417D03*
X1848469Y663317D03*
X1828250Y1128973D03*
X1855006Y1113294D03*
X1881385Y1059938D03*
G54D32*
X72049Y374529D03*
X68109D03*
X72049Y368779D03*
X68109D03*
X72049Y827284D03*
X68109D03*
X72049Y821534D03*
X68109D03*
X72049Y1274290D03*
X68109D03*
X72049Y1280040D03*
X68109D03*
X196261Y374529D03*
X192321D03*
X196261Y368779D03*
X192321D03*
X196261Y827284D03*
X192321D03*
X196261Y821534D03*
X192321D03*
X196261Y1274290D03*
X192321D03*
X196261Y1280040D03*
X192321D03*
X320474Y374529D03*
X316534D03*
X320474Y368779D03*
X316534D03*
X320474Y827284D03*
X316534D03*
X320474Y821534D03*
X316534D03*
X320474Y1274290D03*
X316534D03*
X320474Y1280040D03*
X316534D03*
X444687Y374529D03*
X440747D03*
X444687Y368779D03*
X440747D03*
X444687Y827284D03*
X440747D03*
X444687Y821534D03*
X440747D03*
X444687Y1274290D03*
X440747D03*
X444687Y1280040D03*
X440747D03*
X568899Y374529D03*
X564959D03*
X568899Y368779D03*
X564959D03*
X568899Y827284D03*
X564959D03*
X568899Y821534D03*
X564959D03*
X568899Y1274290D03*
X564959D03*
X568899Y1280040D03*
X564959D03*
X693112Y374529D03*
X689172D03*
X693112Y368779D03*
X689172D03*
X693112Y827284D03*
X689172D03*
X693112Y821534D03*
X689172D03*
X693112Y1274290D03*
X689172D03*
X693112Y1280040D03*
X689172D03*
X1242718Y374529D03*
X1238778D03*
X1242718Y368779D03*
X1238778D03*
X1242718Y827284D03*
X1238778D03*
X1242718Y821534D03*
X1238778D03*
X1242718Y1274290D03*
X1238778D03*
X1242718Y1280040D03*
X1238778D03*
X1366931Y374529D03*
X1362991D03*
X1366931Y368779D03*
X1362991D03*
X1366931Y827284D03*
X1362991D03*
X1366931Y821534D03*
X1362991D03*
X1366931Y1274290D03*
X1362991D03*
X1366931Y1280040D03*
X1362991D03*
X1491143Y374529D03*
X1487203D03*
X1491143Y368779D03*
X1487203D03*
X1491143Y827284D03*
X1487203D03*
X1491143Y821534D03*
X1487203D03*
X1491143Y1274290D03*
X1487203D03*
X1491143Y1280040D03*
X1487203D03*
X1615356Y374529D03*
X1611416D03*
X1615356Y368779D03*
X1611416D03*
X1615356Y827284D03*
X1611416D03*
X1615356Y821534D03*
X1611416D03*
X1615356Y1274290D03*
X1611416D03*
X1615356Y1280040D03*
X1611416D03*
X1739568Y374529D03*
X1735628D03*
X1739568Y368779D03*
X1735628D03*
X1739568Y827284D03*
X1735628D03*
X1739568Y821534D03*
X1735628D03*
X1739568Y1274290D03*
X1735628D03*
X1739568Y1280040D03*
X1735628D03*
X1859841Y374529D03*
Y368779D03*
Y827284D03*
Y821534D03*
Y1274290D03*
Y1280040D03*
X1863781Y374529D03*
Y368779D03*
Y827284D03*
Y821534D03*
Y1274290D03*
Y1280040D03*
G54D23*
X60137Y210561D03*
X61784Y513020D03*
X47557Y513016D03*
X60137Y663317D03*
Y1116073D03*
X92137Y176661D03*
Y181161D03*
Y633917D03*
X104263Y985725D03*
X120397Y995001D03*
X105563Y1003325D03*
X92237Y1082173D03*
Y1086673D03*
X142637Y244761D03*
Y697517D03*
X140563Y1005625D03*
X128763Y1001725D03*
X140522Y997250D03*
X127855Y992723D03*
X142637Y1150273D03*
X184349Y210561D03*
X216449Y181361D03*
Y176661D03*
X186038Y512878D03*
X171811Y512874D03*
X207263Y593625D03*
X195463Y589725D03*
X207222Y585250D03*
X187097Y583001D03*
X194555Y580723D03*
X172263Y591025D03*
X170963Y573725D03*
X216449Y623417D03*
Y618917D03*
X206200Y650000D03*
X190099Y667589D03*
X216449Y1082173D03*
Y1086873D03*
X190149Y1119573D03*
X308562Y210561D03*
X266849Y244761D03*
X310209Y512878D03*
X295982Y512874D03*
X308562Y663317D03*
X266849Y697517D03*
X308562Y1116073D03*
X266849Y1150273D03*
X319121Y72855D03*
X329479Y72845D03*
X340762Y176461D03*
X340662Y181161D03*
Y634017D03*
X340762Y1082073D03*
Y1086773D03*
X391062Y244761D03*
Y697517D03*
Y1150273D03*
X432774Y210561D03*
X434359Y512841D03*
X420132Y512837D03*
X432774Y663317D03*
X453374Y1112973D03*
X447373Y1091326D03*
X464874Y176461D03*
Y181161D03*
Y633917D03*
X503274Y1145973D03*
X515274Y244661D03*
X545079Y528531D03*
Y532831D03*
X528677Y512878D03*
X514450Y512874D03*
X547579Y566531D03*
Y561531D03*
X515274Y697417D03*
X589087Y176661D03*
Y181361D03*
X556987Y210661D03*
X604979Y538831D03*
Y542831D03*
X579479Y566331D03*
X571479D03*
X598979Y552331D03*
X589087Y634017D03*
Y629417D03*
X556987Y663417D03*
X589087Y1082173D03*
Y1086873D03*
X556987Y1116173D03*
X625097Y107633D03*
X615101Y112329D03*
X639487Y244761D03*
X642084Y512541D03*
X627857Y512537D03*
X619510Y562574D03*
Y555174D03*
X639487Y697517D03*
Y1150273D03*
X681200Y210561D03*
X681700Y665817D03*
X687000Y1119973D03*
X713300Y176461D03*
Y181161D03*
Y633917D03*
Y629417D03*
Y1081973D03*
Y1086673D03*
X752900Y205500D03*
X751700Y677700D03*
X842400Y1538800D03*
X878250Y359100D03*
X878054Y445462D03*
X878100Y450200D03*
Y454900D03*
X878200Y471100D03*
X878154Y459562D03*
X878143Y464505D03*
X879343Y542405D03*
X889303Y856727D03*
X872072Y1358528D03*
X881312Y1380412D03*
X881311Y1375746D03*
X871908Y1523720D03*
X910300Y1512600D03*
Y1508100D03*
X940700Y1552700D03*
X919700Y1539200D03*
X916700Y1544200D03*
X972090Y1153500D03*
X948700Y1552700D03*
X979913Y1553466D03*
Y1549366D03*
X968232Y1538282D03*
X971200Y1529200D03*
Y1525200D03*
X1019032Y-66200D03*
X1007532Y-43500D03*
X1014850Y550000D03*
X1028635Y908603D03*
X1028600Y904200D03*
X1013200Y930500D03*
X1038074Y1354526D03*
X1042258Y-71536D03*
X1065521Y-76578D03*
X1066304Y79465D03*
X1049700Y442000D03*
X1049737Y429753D03*
X1049701Y434409D03*
X1049915Y557053D03*
X1113300Y-89600D03*
X1113321Y-85538D03*
X1104279Y-82462D03*
X1224910Y236291D03*
X1198050Y284750D03*
X1197829Y1033731D03*
Y1029031D03*
X1253461Y513463D03*
X1239324Y513432D03*
X1258200Y697850D03*
X1253925Y966004D03*
X1239776Y965973D03*
X1258200Y1150173D03*
X1311700Y191161D03*
Y643917D03*
Y1096673D03*
X1335200Y223661D03*
X1349813Y513334D03*
X1335676Y513303D03*
X1335200Y676417D03*
X1352246Y965705D03*
X1338205Y965825D03*
X1335200Y1129173D03*
X1384409Y244829D03*
X1435913Y191161D03*
X1459413Y223661D03*
X1438900Y526100D03*
X1435913Y643917D03*
X1459413Y676417D03*
X1462417Y965883D03*
X1459413Y1129173D03*
X1435913Y1096673D03*
X1476458Y965763D03*
X1560125Y191161D03*
X1555125Y645917D03*
X1552525Y1132273D03*
X1583625Y223661D03*
X1600695Y513418D03*
X1586558Y513387D03*
X1583625Y676417D03*
X1600771Y965889D03*
X1586630Y965809D03*
X1684338Y191161D03*
X1707838Y223661D03*
X1711023Y513134D03*
X1684338Y643917D03*
X1707838Y676417D03*
X1684338Y1096673D03*
X1707838Y1129173D03*
X1725160Y513165D03*
X1763200Y720500D03*
X1763334Y965756D03*
X1749136Y965664D03*
X1762197Y1007001D03*
X1747363Y1015325D03*
X1746063Y997725D03*
X1808550Y191161D03*
Y643917D03*
X1806027Y965626D03*
X1793838Y968689D03*
X1770563Y1013725D03*
X1782322Y1009250D03*
X1769655Y1004723D03*
X1782363Y1017625D03*
X1808550Y1096673D03*
X1851869Y210461D03*
X1845517Y181175D03*
X1832050Y223661D03*
X1848995Y513292D03*
X1834858Y513261D03*
X1845617Y633931D03*
X1832050Y676417D03*
X1851869Y663317D03*
X1831650Y1128973D03*
X1858406Y1113294D03*
X1884785Y1059938D03*
G54D50*
X317812Y103731D03*
X591779Y539031D03*
X568779Y516531D03*
X621058Y538945D03*
X696787Y584595D03*
X752500Y1140200D03*
X870163Y840253D03*
X943500Y1008900D03*
X928384Y1349782D03*
X928439Y1363514D03*
X942925Y1372857D03*
X938000Y1502900D03*
X948845Y934950D03*
X961000Y1525400D03*
X1031563Y856553D03*
X992994Y1009540D03*
X1021200Y1100800D03*
X1068700Y1101800D03*
X1111600Y1101600D03*
X1317655Y112751D03*
X1376243Y574719D03*
X1460200Y518300D03*
X1452200D03*
X1439200D03*
X1465700D03*
X1433200Y562800D03*
X1487541Y535562D03*
X1883000Y187444D03*
Y640200D03*
G54D14*
X25000Y1195200D03*
X30000D03*
X95437Y290361D03*
Y743117D03*
Y1195873D03*
X135422Y1195737D03*
X140422D03*
X219649Y290361D03*
Y743117D03*
X259594Y1195568D03*
X264594D03*
X219649Y1195873D03*
X343862Y290361D03*
Y743117D03*
Y1195873D03*
X383849Y1195442D03*
X388849D03*
X468074Y290361D03*
Y743117D03*
X508103Y1195357D03*
X468074Y1195873D03*
X513103Y1195357D03*
X592287Y290361D03*
X584279Y567031D03*
X592287Y743117D03*
Y1195873D03*
X607460Y560974D03*
X632316Y1195274D03*
X637316D03*
X716500Y290361D03*
Y743117D03*
Y1195873D03*
X751209Y159828D03*
X752500Y1157700D03*
X881256Y1365150D03*
X933524Y922100D03*
X967813Y1553966D03*
X953500Y1553400D03*
X1211205Y1156394D03*
X1216205D03*
X1298500Y260361D03*
Y289861D03*
Y742617D03*
Y713117D03*
Y1165873D03*
Y1195373D03*
X1351321Y1156353D03*
X1346321D03*
X1422713Y260361D03*
Y289861D03*
X1426419Y526957D03*
X1422713Y742617D03*
Y713117D03*
Y1165873D03*
Y1195373D03*
X1470953Y1156227D03*
X1475953D03*
X1507037Y528103D03*
X1546925Y260361D03*
Y289861D03*
Y742617D03*
Y713117D03*
Y1165873D03*
Y1195373D03*
X1615552Y1156406D03*
X1620236D03*
X1671138Y260361D03*
Y289861D03*
Y742617D03*
Y713117D03*
Y1165873D03*
Y1195373D03*
X1760500Y725200D03*
X1723117Y1156353D03*
X1718117D03*
X1795350Y260361D03*
Y289861D03*
X1795468Y742794D03*
X1795350Y713117D03*
Y1165873D03*
Y1195373D03*
X1836400Y1155900D03*
X1841084Y1155921D03*
X1887169Y290361D03*
Y743117D03*
Y1195873D03*
G54D41*
X83237Y247161D03*
Y699917D03*
Y1152673D03*
X130863Y997225D03*
X207449Y247161D03*
X197563Y585225D03*
X207449Y699917D03*
Y1152673D03*
X331662Y247161D03*
Y699917D03*
Y1152673D03*
X455874Y247161D03*
Y699917D03*
X530097Y553231D03*
X580087Y247161D03*
X575329Y506627D03*
X598579Y547831D03*
X580087Y699917D03*
Y1152673D03*
X704300Y247161D03*
Y699917D03*
Y1152673D03*
X874400Y1482760D03*
X957613Y1495424D03*
X967801Y1533926D03*
X1014500Y935000D03*
X1256300Y256161D03*
X1254300Y708917D03*
X1255600Y1161800D03*
X1378513Y708917D03*
X1380513Y256161D03*
X1379800Y1161700D03*
X1502825Y256061D03*
X1502725Y708917D03*
X1504500Y1161700D03*
X1628538Y256061D03*
X1626938Y708917D03*
X1638938Y1161673D03*
X1753350Y256061D03*
X1752500Y1161800D03*
X1772663Y1009225D03*
X1874969Y247161D03*
Y699917D03*
X1876448Y1133143D03*
G54D42*
X77637Y247161D03*
Y699917D03*
Y1152673D03*
X125263Y997225D03*
X201849Y247161D03*
X191963Y585225D03*
X201849Y699917D03*
Y1152673D03*
X326062Y247161D03*
Y699917D03*
Y1152673D03*
X450274Y247161D03*
Y699917D03*
X524497Y553231D03*
X574487Y247161D03*
X569729Y506627D03*
X592979Y547831D03*
X574487Y699917D03*
Y1152673D03*
X698700Y247161D03*
Y699917D03*
Y1152673D03*
X868800Y1482760D03*
X952013Y1495424D03*
X962201Y1533926D03*
X1008900Y935000D03*
X1250700Y256161D03*
X1248700Y708917D03*
X1250000Y1161800D03*
X1374913Y256161D03*
X1372913Y708917D03*
X1374200Y1161700D03*
X1497225Y256061D03*
X1497125Y708917D03*
X1498900Y1161700D03*
X1622938Y256061D03*
X1621338Y708917D03*
X1633338Y1161673D03*
X1747750Y256061D03*
X1746900Y1161800D03*
X1767063Y1009225D03*
X1869369Y247161D03*
Y699917D03*
X1870848Y1133143D03*
G54D33*
X43728Y499434D03*
X57963Y499397D03*
X47603Y506934D03*
X39853D03*
X61838Y506897D03*
X54088D03*
X167982Y499392D03*
X164107Y506892D03*
X182217Y499355D03*
X171857Y506892D03*
X186092Y506855D03*
X178342D03*
X292153Y499392D03*
X306388Y499355D03*
X296028Y506892D03*
X288278D03*
X310263Y506855D03*
X302513D03*
X416303Y499355D03*
X430538Y499318D03*
X420178Y506855D03*
X412428D03*
X434413Y506818D03*
X426663D03*
X506746Y506892D03*
X510621Y499392D03*
X524856Y499355D03*
X514496Y506892D03*
X528731Y506855D03*
X520981D03*
X624028Y499055D03*
X638263Y499018D03*
X627903Y506555D03*
X620153D03*
X642138Y506518D03*
X634388D03*
X858500Y1511250D03*
X862375Y1518750D03*
X854625D03*
X868458Y1529687D03*
X872333Y1537187D03*
X864583D03*
X937399Y897695D03*
X941274Y905195D03*
X933524D03*
X1239758Y499401D03*
X1253867Y499400D03*
X1243633Y506901D03*
X1235883D03*
X1257742Y506900D03*
X1249992D03*
X1240222Y951942D03*
X1244097Y959442D03*
X1236347D03*
X1254331Y951941D03*
X1258206Y959441D03*
X1250456D03*
X1336110Y499272D03*
X1350219Y499271D03*
X1339985Y506772D03*
X1332235D03*
X1354094Y506771D03*
X1346344D03*
X1338611Y952153D03*
X1342486Y959653D03*
X1334736D03*
X1352803Y952194D03*
X1356678Y959694D03*
X1348928D03*
X1453451Y499121D03*
X1472480Y499018D03*
X1457326Y506621D03*
X1449576D03*
X1468605Y506518D03*
X1462823Y952111D03*
X1466698Y959611D03*
X1458948D03*
X1473140Y959652D03*
X1476355Y506518D03*
X1477015Y952152D03*
X1480890Y959652D03*
X1586992Y499356D03*
X1601101Y499355D03*
X1590867Y506856D03*
X1583117D03*
X1604976Y506855D03*
X1597226D03*
X1587036Y952237D03*
X1590911Y959737D03*
X1583161D03*
X1601228Y952278D03*
X1605103Y959778D03*
X1597353D03*
X1711457Y499103D03*
X1715332Y506603D03*
X1707582D03*
X1725566Y499102D03*
X1729441Y506602D03*
X1721691D03*
X1749573Y952193D03*
X1753448Y959693D03*
X1745698D03*
X1763765Y952234D03*
X1759890Y959734D03*
X1792236Y951851D03*
X1796111Y959351D03*
X1788361D03*
X1806452Y952110D03*
X1810327Y959610D03*
X1802577D03*
X1767640Y959734D03*
X1835292Y499230D03*
X1849401Y499229D03*
X1839167Y506730D03*
X1831417D03*
X1853276Y506729D03*
X1845526D03*
G54D60*
X575700Y533081D03*
X573732D03*
X571763D03*
X569795D03*
X567826D03*
X565858D03*
Y552581D03*
X567826D03*
X569795D03*
X571763D03*
X573732D03*
X575700D03*
X942953Y1519450D03*
X940984D03*
X939016D03*
X937047D03*
X935079D03*
Y1538950D03*
X937047D03*
X939016D03*
X940984D03*
X942953D03*
X944921Y1519450D03*
Y1538950D03*
X1462121Y539850D03*
X1460153D03*
X1458184D03*
X1456216D03*
X1454247D03*
X1452279D03*
Y559350D03*
X1454247D03*
X1456216D03*
X1458184D03*
X1460153D03*
X1462121D03*
G54D24*
X66437Y188161D03*
Y179161D03*
Y631917D03*
Y640917D03*
Y1084673D03*
Y1093673D03*
X190649Y188161D03*
Y179161D03*
X194749Y621417D03*
Y630417D03*
X190651Y1086035D03*
Y1095035D03*
X314862Y188161D03*
Y179161D03*
Y631917D03*
Y640917D03*
Y1084673D03*
Y1093673D03*
X439074Y188161D03*
Y179161D03*
Y631917D03*
Y640917D03*
X513517Y576931D03*
Y567931D03*
X563287Y188161D03*
Y179161D03*
Y631917D03*
Y640917D03*
Y1084673D03*
Y1093673D03*
X687500Y188161D03*
Y179161D03*
X691600Y631917D03*
Y640917D03*
X687500Y1084673D03*
Y1093673D03*
X882500Y1522868D03*
Y1531868D03*
X1087700Y-51200D03*
Y-42200D03*
X1514297Y544511D03*
Y553511D03*
G54D51*
X317812Y107331D03*
X591779Y542631D03*
X568779Y520131D03*
X621058Y542545D03*
X696787Y588195D03*
X752500Y1143800D03*
X870163Y843853D03*
X943500Y1012500D03*
X928384Y1353382D03*
X928439Y1367114D03*
X942925Y1376457D03*
X938000Y1506500D03*
X948845Y938550D03*
X961000Y1529000D03*
X1031563Y860153D03*
X992994Y1013140D03*
X1021200Y1104400D03*
X1068700Y1105400D03*
X1111600Y1105200D03*
X1317655Y116351D03*
X1376243Y578319D03*
X1460200Y521900D03*
X1452200D03*
X1439200D03*
X1465700D03*
X1433200Y566400D03*
X1487541Y539162D03*
X1883000Y191044D03*
Y643800D03*
G54D15*
X35506Y-110687D03*
X63128Y89671D03*
X60754Y1316385D03*
X72380Y1596505D03*
X1861177Y91072D03*
X1874818Y-110232D03*
G54D25*
X64437Y209361D03*
Y662017D03*
Y1114773D03*
X138428Y966735D03*
X188649Y209061D03*
X205128Y554735D03*
X188349Y1110473D03*
X312862Y209161D03*
Y661917D03*
Y1114773D03*
X437074Y209161D03*
X437174Y661917D03*
X504674Y1114573D03*
X561387Y209161D03*
Y661917D03*
X561287Y1114673D03*
X685500Y209261D03*
Y662017D03*
X685200Y1110373D03*
X870963Y818831D03*
X869863Y1487165D03*
X1032430Y834829D03*
X1009900Y939000D03*
X1182540Y257688D03*
X1177965Y281343D03*
X1228892Y225125D03*
X1253200Y240661D03*
X1251200Y693417D03*
Y1146173D03*
X1377413Y240661D03*
X1375413Y693417D03*
Y1146173D03*
X1499725Y240561D03*
X1499625Y693417D03*
Y1146173D03*
X1625438Y240561D03*
X1623838Y693417D03*
X1635638Y1146173D03*
X1750250Y240561D03*
X1748050Y1146173D03*
X1780228Y978735D03*
X1856169Y209161D03*
Y661917D03*
X1856391Y1102987D03*
G54D70*
X871346Y86000D03*
X860378D03*
X1178334Y726750D03*
X1187784Y47968D03*
X1198752D03*
X1189302Y726750D03*
G54D43*
X94237Y284461D03*
Y276861D03*
Y737217D03*
Y729617D03*
Y1189973D03*
Y1182373D03*
X218449Y284461D03*
Y276861D03*
Y737217D03*
Y729617D03*
Y1189973D03*
Y1182373D03*
X342662Y284461D03*
Y276861D03*
Y737217D03*
Y729617D03*
Y1189973D03*
Y1182373D03*
X466874Y284461D03*
Y276861D03*
Y737217D03*
Y729617D03*
Y1189973D03*
Y1182373D03*
X591087Y284461D03*
Y276861D03*
X587974Y513895D03*
Y521495D03*
X563279Y519131D03*
Y511531D03*
X591087Y737217D03*
Y729617D03*
Y1189973D03*
Y1182373D03*
X715300Y284461D03*
Y276861D03*
Y737217D03*
Y729617D03*
Y1189973D03*
Y1182373D03*
X880200Y693200D03*
Y700800D03*
X932500Y1505500D03*
Y1497900D03*
X964035Y1496252D03*
Y1503852D03*
X956286Y1502925D03*
Y1510525D03*
X1018483Y1460325D03*
Y1467925D03*
X1074455Y1459711D03*
Y1467311D03*
X1046355Y1459711D03*
Y1467311D03*
X1313000Y287361D03*
Y294961D03*
X1305000Y287361D03*
Y294961D03*
X1313000Y740117D03*
X1305000D03*
X1313000Y747717D03*
X1305000D03*
X1313000Y1192873D03*
Y1200473D03*
X1305000Y1192873D03*
Y1200473D03*
X1402257Y549931D03*
Y542331D03*
X1437213Y287361D03*
Y294961D03*
X1429213Y287361D03*
Y294961D03*
X1441631Y581215D03*
Y573615D03*
X1464700Y573300D03*
Y580900D03*
X1437213Y740117D03*
X1429213D03*
X1437213Y747717D03*
X1429213D03*
X1437213Y1192873D03*
Y1200473D03*
X1429213Y1192873D03*
Y1200473D03*
X1561425Y287361D03*
Y294961D03*
X1553425Y287361D03*
Y294961D03*
X1561425Y740117D03*
X1553425D03*
X1561425Y747717D03*
X1553425D03*
Y1192873D03*
Y1200473D03*
X1561425Y1192873D03*
Y1200473D03*
X1685638Y287361D03*
Y294961D03*
X1677638Y287361D03*
Y294961D03*
X1685638Y740117D03*
X1677638D03*
X1685638Y747717D03*
X1677638D03*
X1685638Y1192873D03*
Y1200473D03*
X1677638Y1192873D03*
Y1200473D03*
X1809850Y287361D03*
Y294961D03*
X1801850Y287361D03*
Y294961D03*
X1809968Y740294D03*
X1801968D03*
X1809968Y747894D03*
X1801968D03*
X1809850Y1192873D03*
Y1200473D03*
X1801850Y1192873D03*
Y1200473D03*
X1885969Y284461D03*
Y276861D03*
Y737217D03*
Y729617D03*
X1865992Y1146330D03*
Y1138730D03*
X1885969Y1189973D03*
Y1182373D03*
G54D61*
X570779Y542831D03*
X940000Y1529200D03*
X1457200Y549600D03*
G54D52*
X460873Y1081266D03*
X453473D03*
X460873Y1083826D03*
Y1086386D03*
X453473D03*
Y1083826D03*
X1303800Y180721D03*
Y178161D03*
Y175601D03*
X1311200D03*
Y178161D03*
Y180721D03*
X1303800Y633477D03*
Y630917D03*
Y628357D03*
X1311200D03*
Y630917D03*
Y633477D03*
X1303800Y1081113D03*
X1311200D03*
X1303800Y1086233D03*
Y1083673D03*
X1311200D03*
Y1086233D03*
X1428013Y180721D03*
Y178161D03*
Y175601D03*
Y633477D03*
Y630917D03*
Y628357D03*
Y1081113D03*
Y1086233D03*
Y1083673D03*
X1435413Y175601D03*
Y178161D03*
Y180721D03*
Y628357D03*
Y630917D03*
Y633477D03*
Y1081113D03*
Y1083673D03*
Y1086233D03*
X1552225Y180721D03*
Y178161D03*
Y175601D03*
X1559625D03*
Y178161D03*
Y180721D03*
X1552225Y633477D03*
Y630917D03*
Y628357D03*
X1559625D03*
Y630917D03*
Y633477D03*
X1552225Y1081113D03*
X1559625D03*
X1552225Y1086233D03*
Y1083673D03*
X1559625D03*
Y1086233D03*
X1676438Y180721D03*
Y178161D03*
Y175601D03*
X1683838D03*
Y178161D03*
Y180721D03*
X1676438Y633477D03*
Y630917D03*
Y628357D03*
X1683838D03*
Y630917D03*
Y633477D03*
X1676438Y1081113D03*
X1683838D03*
X1676438Y1086233D03*
Y1083673D03*
X1683838D03*
Y1086233D03*
X1800650Y180721D03*
Y178161D03*
Y175601D03*
X1808050D03*
Y178161D03*
Y180721D03*
X1800650Y633477D03*
Y630917D03*
Y628357D03*
X1808050D03*
Y630917D03*
Y633477D03*
X1800650Y1081113D03*
X1808050D03*
X1800650Y1086233D03*
Y1083673D03*
X1808050D03*
Y1086233D03*
X1859117Y171015D03*
Y173575D03*
Y176135D03*
X1851717D03*
Y173575D03*
Y171015D03*
X1859117Y623771D03*
Y626331D03*
Y628891D03*
X1851717D03*
Y626331D03*
Y623771D03*
X1871030Y1076940D03*
Y1079500D03*
Y1082060D03*
X1863630D03*
Y1079500D03*
Y1076940D03*
G54D34*
X72500Y498200D03*
X67500D03*
X72500Y950955D03*
X67500D03*
X126063Y974025D03*
X196712Y498200D03*
X191712D03*
X192763Y562025D03*
X216712Y950755D03*
X221712D03*
X313312Y103231D03*
X320925Y498200D03*
X315925D03*
X320925Y950955D03*
X315925D03*
X445138Y498200D03*
X440138D03*
X445138Y950955D03*
X440138D03*
X539350Y498200D03*
X534350D03*
X520479Y558913D03*
X569350Y950955D03*
X564350D03*
X652663Y506200D03*
X647663D03*
X607460Y550474D03*
X693563Y950955D03*
X688563D03*
X749000Y666200D03*
X865663Y838753D03*
X892700Y1534118D03*
X939000Y1007400D03*
X944776Y935200D03*
X987970Y1008207D03*
X967813Y1543366D03*
X1027063Y855053D03*
X1017000Y1099200D03*
X1064500Y1100200D03*
X1094200Y-48400D03*
X1107100Y1100100D03*
X1269878Y498621D03*
X1264878D03*
X1268742Y950786D03*
X1263742D03*
X1312999Y111325D03*
X1364882Y498200D03*
X1359882D03*
X1367382Y950955D03*
X1362382D03*
X1426419Y516457D03*
X1443700Y519800D03*
X1491594Y498200D03*
X1486594D03*
X1491594Y950955D03*
X1486594D03*
X1615807Y498200D03*
X1610807D03*
X1615807Y950955D03*
X1610807D03*
X1740019Y498200D03*
X1735019D03*
X1740019Y950955D03*
X1735019D03*
X1767863Y986025D03*
X1782666Y950944D03*
X1777666D03*
X1859232Y498200D03*
X1869500Y184944D03*
X1864232Y498200D03*
X1869500Y637700D03*
G54D16*
X59937Y187361D03*
Y640117D03*
Y1092873D03*
X108363Y998925D03*
X112500Y998980D03*
X184149Y187461D03*
X175063Y586925D03*
X179200Y586980D03*
X188649Y629617D03*
X306955Y71879D03*
X314370Y125341D03*
X308362Y187461D03*
X308262Y640217D03*
Y1092973D03*
X323813Y125322D03*
X328321Y125299D03*
X318909Y125343D03*
X333021Y125355D03*
X365162Y84670D03*
X432574Y187461D03*
Y640117D03*
X447173Y1075426D03*
X442473D03*
X556787Y187361D03*
X549279Y520031D03*
X553279D03*
X556787Y640117D03*
Y1092973D03*
X580279Y520031D03*
X557279Y567031D03*
X592779Y574031D03*
X579718Y574097D03*
X571540Y574065D03*
X615100Y520300D03*
X611910Y565974D03*
X637213Y589355D03*
X681000Y187361D03*
X685500Y640117D03*
X680400Y1101000D03*
X878673Y811303D03*
X883400Y811332D03*
X881448Y1358507D03*
X881420Y1350388D03*
X882000Y1439200D03*
X873000D03*
X893050Y1486000D03*
X879321Y1485961D03*
X883947Y1485970D03*
X860000Y1504700D03*
X850500D03*
X914600Y912400D03*
X927861Y962907D03*
X921600Y981900D03*
X916500Y962800D03*
X925053Y1032085D03*
X916769Y1032139D03*
X936959Y1366990D03*
X936964Y1353312D03*
X932294Y1376548D03*
X922500Y1506400D03*
X918500D03*
X941000Y1560400D03*
X926500Y1553400D03*
X957000Y911700D03*
X970500D03*
X952500D03*
X954900Y957100D03*
X950400D03*
X959400D03*
X955000Y982700D03*
X964000D03*
X945790Y953862D03*
X955700Y1027500D03*
X951200D03*
X946700D03*
X947159Y1365287D03*
X951525Y1376357D03*
X950300Y1506400D03*
X988573Y1509912D03*
X962000Y1560400D03*
X949000D03*
X972413Y1556866D03*
X1038712Y-38558D03*
X1004100Y-70032D03*
X1035973Y830903D03*
X1034400Y908400D03*
X1002194Y981540D03*
X1006694D03*
X1007849Y1030543D03*
X1003194Y1030540D03*
X993649Y1030543D03*
X1012494Y1030640D03*
X998439Y1030537D03*
X1028000Y1073700D03*
X1022400Y1121500D03*
X1031400D03*
X1026900D03*
X1017800Y1144200D03*
X1008700D03*
X995000D03*
X1009500Y1187700D03*
X1014500D03*
X1004500D03*
X1061325Y-44000D03*
X1074400Y-42332D03*
X1040773Y830903D03*
X1054419Y835653D03*
X1048400Y908400D03*
X1057700D03*
X1064918Y942349D03*
X1069918D03*
X1087000Y1073700D03*
X1078000D03*
X1041500D03*
X1087700Y1122600D03*
X1074500Y1122700D03*
X1079000D03*
X1070155Y1122703D03*
X1083355D03*
X1115200Y1073800D03*
X1128900D03*
X1119500Y1121900D03*
X1124100D03*
X1115000D03*
X1176100Y266200D03*
X1176835Y614632D03*
X1192300Y268568D03*
X1194600Y296100D03*
X1197100Y275900D03*
X1250410Y236409D03*
X1327921Y86155D03*
X1299569Y90891D03*
X1315115Y133800D03*
X1324207Y133803D03*
X1319797Y133788D03*
X1328534D03*
X1312000Y169361D03*
X1322000D03*
X1326400Y181761D03*
X1321900D03*
X1312000Y622117D03*
X1322000D03*
X1326500Y634517D03*
X1322000D03*
X1309600Y1074873D03*
X1317400Y1074900D03*
X1326500Y1087273D03*
X1322000D03*
X1332934Y133788D03*
X1421969Y531357D03*
X1436213Y169361D03*
X1446213D03*
X1450713Y181761D03*
X1446013D03*
X1463085Y506585D03*
X1452200Y575800D03*
X1470700D03*
X1437200Y566300D03*
X1436213Y622117D03*
X1446213D03*
X1450713Y634517D03*
X1446013D03*
X1436213Y1074873D03*
X1446213D03*
X1450713Y1087273D03*
X1446013D03*
X1502400Y550850D03*
X1481938Y506470D03*
X1560425Y169361D03*
X1570425D03*
X1570125Y181761D03*
X1560425Y622117D03*
X1570425D03*
X1570225Y634517D03*
X1560425Y1074873D03*
X1570425D03*
Y1087373D03*
X1574925Y181761D03*
Y634517D03*
Y1087373D03*
X1684638Y169361D03*
X1694638D03*
X1699138Y181761D03*
X1694438D03*
X1684638Y622117D03*
X1694638D03*
X1699138Y634517D03*
X1694438D03*
X1684638Y1074873D03*
X1694638D03*
X1699138Y1087273D03*
X1694438D03*
X1750163Y1010925D03*
X1754300Y1010980D03*
X1808850Y169361D03*
Y622117D03*
X1805250Y1074673D03*
X1818850Y169361D03*
X1823350Y181761D03*
X1818650D03*
X1845517Y165175D03*
X1841017D03*
X1818850Y622117D03*
X1823350Y634517D03*
X1818650D03*
X1845417Y617931D03*
X1840917D03*
X1815250Y1074673D03*
X1823350Y1087273D03*
X1818650D03*
X1838074Y1092395D03*
X1836200Y1136620D03*
X1878900Y190944D03*
Y643700D03*
X1876662Y1062126D03*
X1872162D03*
G54D26*
X68037Y209361D03*
Y662017D03*
Y1114773D03*
X142028Y966735D03*
X192249Y209061D03*
X208728Y554735D03*
X191949Y1110473D03*
X316462Y209161D03*
Y661917D03*
Y1114773D03*
X440674Y209161D03*
X440774Y661917D03*
X508274Y1114573D03*
X564987Y209161D03*
Y661917D03*
X564887Y1114673D03*
X689100Y209261D03*
Y662017D03*
X688800Y1110373D03*
X874563Y818831D03*
X873463Y1487165D03*
X1036030Y834829D03*
X1013500Y939000D03*
X1181565Y281343D03*
X1186140Y257688D03*
X1232492Y225125D03*
X1256800Y240661D03*
X1254800Y693417D03*
Y1146173D03*
X1381013Y240661D03*
X1379013Y693417D03*
Y1146173D03*
X1503325Y240561D03*
X1503225Y693417D03*
Y1146173D03*
X1629038Y240561D03*
X1627438Y693417D03*
X1639238Y1146173D03*
X1753850Y240561D03*
X1751650Y1146173D03*
X1783828Y978735D03*
X1859769Y209161D03*
Y661917D03*
X1859991Y1102987D03*
G54D71*
X870100Y691616D03*
Y702584D03*
G54D53*
X445173Y1097726D03*
X454173D03*
X1323500Y188161D03*
Y640917D03*
Y1093673D03*
X1332500Y188161D03*
Y640917D03*
Y1093673D03*
X1447713Y188161D03*
X1456713D03*
X1447713Y640917D03*
X1456713D03*
X1447713Y1093673D03*
X1456713D03*
X1571925Y188161D03*
X1566925Y642917D03*
X1580925Y188161D03*
X1575925Y642917D03*
X1581025Y1087373D03*
X1590025D03*
X1696138Y188161D03*
X1705138D03*
X1696138Y640917D03*
X1705138D03*
X1696138Y1093673D03*
X1705138D03*
X1843417Y187575D03*
X1852417D03*
X1820350Y188161D03*
X1829350D03*
X1843417Y640331D03*
X1852417D03*
X1820350Y640917D03*
X1829350D03*
X1843896Y1092413D03*
X1852896D03*
X1820350Y1093673D03*
X1829350D03*
G54D35*
X72500Y503800D03*
X67500D03*
X72500Y956555D03*
X67500D03*
X126063Y979625D03*
X196712Y503800D03*
X191712D03*
X192763Y567625D03*
X216712Y956355D03*
X221712D03*
X313312Y108831D03*
X320925Y503800D03*
X315925D03*
X320925Y956555D03*
X315925D03*
X445138Y503800D03*
X440138D03*
X445138Y956555D03*
X440138D03*
X539350Y503800D03*
X534350D03*
X520479Y564513D03*
X569350Y956555D03*
X564350D03*
X652663Y511800D03*
X647663D03*
X607460Y556074D03*
X693563Y956555D03*
X688563D03*
X749000Y671800D03*
X865663Y844353D03*
X892700Y1539718D03*
X939000Y1013000D03*
X944776Y940800D03*
X987970Y1013807D03*
X967813Y1548966D03*
X1027063Y860653D03*
X1017000Y1104800D03*
X1064500Y1105800D03*
X1094200Y-42800D03*
X1107100Y1105700D03*
X1269878Y504221D03*
X1264878D03*
X1268742Y956386D03*
X1263742D03*
X1312999Y116925D03*
X1364882Y503800D03*
X1359882D03*
X1367382Y956555D03*
X1362382D03*
X1426419Y522057D03*
X1443700Y525400D03*
X1491594Y503800D03*
X1486594D03*
X1491594Y956555D03*
X1486594D03*
X1615807Y503800D03*
X1610807D03*
X1615807Y956555D03*
X1610807D03*
X1740019Y503800D03*
X1735019D03*
X1740019Y956555D03*
X1735019D03*
X1782666Y956544D03*
X1777666D03*
X1767863Y991625D03*
X1859232Y503800D03*
X1869500Y190544D03*
X1864232Y503800D03*
X1869500Y643300D03*
G54D17*
X59937Y183961D03*
Y636717D03*
Y1089473D03*
X108363Y995525D03*
X112500Y995580D03*
X184149Y184061D03*
X175063Y583525D03*
X179200Y583580D03*
X188649Y626217D03*
X306955Y68479D03*
X314370Y121941D03*
X308362Y184061D03*
X308262Y636817D03*
Y1089573D03*
X323813Y121922D03*
X328321Y121899D03*
X318909Y121943D03*
X333021Y121955D03*
X365162Y81270D03*
X432574Y184061D03*
Y636717D03*
X447173Y1072026D03*
X442473D03*
X556787Y183961D03*
X549279Y516631D03*
X553279D03*
X556787Y636717D03*
Y1089573D03*
X580279Y516631D03*
X557279Y563631D03*
X592779Y570631D03*
X579718Y570697D03*
X571540Y570665D03*
X615100Y516900D03*
X611910Y562574D03*
X637213Y585955D03*
X681000Y183961D03*
X685500Y636717D03*
X680400Y1097600D03*
X878673Y807903D03*
X883400Y807932D03*
X881448Y1355107D03*
X881420Y1346988D03*
X882000Y1435800D03*
X873000D03*
X893050Y1482600D03*
X879321Y1482561D03*
X883947Y1482570D03*
X860000Y1501300D03*
X850500D03*
X914600Y909000D03*
X927861Y959507D03*
X921600Y978500D03*
X916500Y959400D03*
X925053Y1028685D03*
X916769Y1028739D03*
X936959Y1363590D03*
X932294Y1373148D03*
X936964Y1349912D03*
X922500Y1503000D03*
X918500D03*
X941000Y1557000D03*
X926500Y1550000D03*
X957000Y908300D03*
X970500D03*
X952500D03*
X954900Y953700D03*
X950400D03*
X959400D03*
X955000Y979300D03*
X964000D03*
X945790Y950462D03*
X955700Y1024100D03*
X951200D03*
X946700D03*
X951525Y1372957D03*
X947159Y1361887D03*
X950300Y1503000D03*
X988573Y1506512D03*
X962000Y1557000D03*
X949000D03*
X972413Y1553466D03*
X1038712Y-41958D03*
X1004100Y-73432D03*
X1035973Y827503D03*
X1034400Y905000D03*
X1002194Y978140D03*
X1006694D03*
X1007849Y1027143D03*
X1003194Y1027140D03*
X993649Y1027143D03*
X1012494Y1027240D03*
X998439Y1027137D03*
X1028000Y1070300D03*
X1022400Y1118100D03*
X1031400D03*
X1026900D03*
X1017800Y1140800D03*
X1008700D03*
X995000D03*
X1009500Y1184300D03*
X1014500D03*
X1004500D03*
X1061325Y-47400D03*
X1074400Y-45732D03*
X1040773Y827503D03*
X1054419Y832253D03*
X1048400Y905000D03*
X1057700D03*
X1064918Y938949D03*
X1069918D03*
X1087000Y1070300D03*
X1078000D03*
X1041500D03*
X1087700Y1119200D03*
X1074500Y1119300D03*
X1079000D03*
X1070155Y1119303D03*
X1083355D03*
X1115200Y1070400D03*
X1128900D03*
X1119500Y1118500D03*
X1124100D03*
X1115000D03*
X1176100Y262800D03*
X1176835Y611232D03*
X1192300Y265168D03*
X1194600Y292700D03*
X1197100Y272500D03*
X1250410Y233009D03*
X1327921Y82755D03*
X1299569Y87491D03*
X1315115Y130400D03*
X1324207Y130403D03*
X1319797Y130388D03*
X1328534D03*
X1312000Y165961D03*
X1322000D03*
X1326400Y178361D03*
X1321900D03*
X1312000Y618717D03*
X1322000D03*
X1326500Y631117D03*
X1322000D03*
X1309600Y1071473D03*
X1317400Y1071500D03*
X1326500Y1083873D03*
X1322000D03*
X1332934Y130388D03*
X1421969Y527957D03*
X1436213Y165961D03*
X1446213D03*
X1450713Y178361D03*
X1446013D03*
X1463085Y503185D03*
X1452200Y572400D03*
X1470700D03*
X1437200Y562900D03*
X1436213Y618717D03*
X1446213D03*
X1450713Y631117D03*
X1446013D03*
X1436213Y1071473D03*
X1446213D03*
X1450713Y1083873D03*
X1446013D03*
X1481938Y503070D03*
X1502400Y547450D03*
X1560425Y165961D03*
X1570425D03*
X1570125Y178361D03*
X1560425Y618717D03*
X1570425D03*
X1570225Y631117D03*
X1560425Y1071473D03*
X1570425D03*
Y1083973D03*
X1574925Y178361D03*
Y631117D03*
Y1083973D03*
X1684638Y165961D03*
X1694638D03*
X1699138Y178361D03*
X1694438D03*
X1684638Y618717D03*
X1694638D03*
X1699138Y631117D03*
X1694438D03*
X1684638Y1071473D03*
X1694638D03*
X1699138Y1083873D03*
X1694438D03*
X1750163Y1007525D03*
X1754300Y1007580D03*
X1808850Y165961D03*
Y618717D03*
X1805250Y1071273D03*
X1845517Y161775D03*
X1841017D03*
X1818850Y165961D03*
X1823350Y178361D03*
X1818650D03*
X1818850Y618717D03*
X1823350Y631117D03*
X1818650D03*
X1845417Y614531D03*
X1840917D03*
X1815250Y1071273D03*
X1823350Y1083873D03*
X1818650D03*
X1838074Y1088995D03*
X1836200Y1133220D03*
X1878900Y187544D03*
Y640300D03*
X1876662Y1058726D03*
X1872162D03*
G54D62*
X601418Y516495D03*
X608918Y520370D03*
Y512620D03*
X975023Y1508212D03*
X982523Y1512087D03*
Y1504337D03*
X1005250Y917500D03*
X1012750Y913625D03*
Y921375D03*
G54D44*
X128909Y171892D03*
X126709D03*
X128909Y174092D03*
X126709D03*
Y624648D03*
X128909D03*
X126709Y626848D03*
X128909D03*
X126709Y1077404D03*
X128909D03*
X126709Y1079604D03*
X128909D03*
X253121Y171892D03*
X250921D03*
X253121Y174092D03*
X250921D03*
Y626848D03*
X253121D03*
X250921Y624648D03*
X253121D03*
X250921Y1077404D03*
X253121D03*
X250921Y1079604D03*
X253121D03*
X377334Y171892D03*
X375134D03*
X377334Y174092D03*
X375134D03*
Y624648D03*
X377334D03*
X375134Y626848D03*
X377334D03*
X375134Y1077404D03*
X377334D03*
X375134Y1079604D03*
X377334D03*
X501546Y174092D03*
X499346D03*
X501546Y171892D03*
X499346D03*
Y624648D03*
X501546D03*
X499346Y626848D03*
X501546D03*
X499346Y1079604D03*
X501546D03*
X499346Y1077404D03*
X501546D03*
X625759Y174092D03*
X623559D03*
X625759Y171892D03*
X623559D03*
Y624648D03*
X625759D03*
X623559Y626848D03*
X625759D03*
X623559Y1077404D03*
X625759D03*
X623559Y1079604D03*
X625759D03*
X747772Y174092D03*
Y171892D03*
Y624648D03*
Y626848D03*
Y1077404D03*
Y1079604D03*
X749972Y174092D03*
Y171892D03*
Y624648D03*
Y626848D03*
Y1077404D03*
Y1079604D03*
G54D80*
X1023290Y1521346D03*
Y1553748D03*
G54D90*
G01X363248Y-425196D02*
Y-505196D01*
G01D02*
X1639148D01*
G01X359248Y-409196D02*
G02I-12000J0D01*
G01X354098D02*
G02I-6850J0D01*
G01X347248Y-425196D02*
Y-393196D01*
G01X363248Y-425196D02*
X1639148D01*
G01X363248Y-460696D02*
X1639148D01*
G01X363248Y-409196D02*
X331248D01*
G01X720748Y-425196D02*
Y-505196D01*
G01X858248Y-425196D02*
Y-505196D01*
G01X973248Y-425196D02*
Y-505196D01*
G01X1271648Y-425196D02*
Y-505196D01*
G01X1441648Y-425196D02*
Y-505196D01*
G01X1639148Y-425196D02*
Y-505196D01*
G01X1667148Y-409196D02*
G02I-12000J0D01*
G01X1661998D02*
G02I-6850J0D01*
G01X1655148Y-425196D02*
Y-393196D01*
G01X1671148Y-409196D02*
X1639148D01*
G54D18*
X72837Y177961D03*
Y630717D03*
Y1083473D03*
X140372Y736524D03*
X133063Y1006025D03*
X197049Y177961D03*
X199763Y594025D03*
X197449Y1083473D03*
X264739Y736268D03*
X337721Y121955D03*
X321362Y177961D03*
X321262Y630717D03*
Y1083473D03*
X365162Y92470D03*
X388796Y736196D03*
X389067Y1166330D03*
X445474Y177961D03*
Y630717D03*
X457173Y1072026D03*
X445573Y1104126D03*
X525579Y541581D03*
X512892Y736449D03*
X569687Y177961D03*
X575779Y516631D03*
X557279D03*
X594267Y530670D03*
X569687Y630717D03*
Y1083473D03*
X611910Y551674D03*
X637326Y736366D03*
X666142Y106519D03*
X693900Y177961D03*
Y1083473D03*
X752500Y1148300D03*
X877673Y861703D03*
X882400Y861668D03*
X876748Y1355107D03*
X876740Y1347014D03*
X882445Y1407597D03*
X877445D03*
X886792Y1407714D03*
X868500Y1435800D03*
X886500D03*
X877500D03*
X888600Y1482550D03*
X923600Y909000D03*
X928100D03*
X919100D03*
X932361Y959507D03*
X920607Y959382D03*
X936861Y959507D03*
X926100Y978500D03*
X930600D03*
X917100D03*
X929105Y1028560D03*
X920879Y1028703D03*
X932559Y1363584D03*
X936994Y1373148D03*
X932564Y1349912D03*
X926500Y1503000D03*
X942000D03*
X896365Y1516592D03*
X896335Y1525008D03*
X961500Y908300D03*
X966000D03*
X963900Y953700D03*
X950500Y979300D03*
X959500D03*
X946000D03*
X960400Y1024100D03*
X947125Y1372957D03*
X951872Y1361902D03*
X946300Y1503000D03*
X963488Y1517039D03*
X972413Y1545966D03*
X1039100Y905000D03*
X1020480Y904800D03*
X1015728D03*
X1023100Y956050D03*
X997694Y978140D03*
X1011194D03*
X993194D03*
X1017194Y1027240D03*
X1032500Y1070300D03*
X1037000D03*
X1023500D03*
X1035900Y1118100D03*
X1013400Y1140800D03*
X1004300D03*
X999700D03*
X1074400Y-77068D03*
X1043112Y-42008D03*
X1066225Y-47400D03*
X1046803Y872727D03*
X1042101Y877241D03*
X1043900Y905000D03*
X1053200D03*
X1073500Y1070300D03*
X1069000D03*
X1082500D03*
X1110500Y1070400D03*
X1119700D03*
X1124500D03*
X1128800Y1118500D03*
X1092200Y1119200D03*
X1176300Y292700D03*
X1180953Y292785D03*
X1176100Y274200D03*
X1176500Y1116800D03*
X1215547Y253315D03*
X1185588Y292750D03*
X1190200Y292700D03*
X1199000Y292300D03*
X1323521Y82755D03*
X1318821D03*
X1304563Y87558D03*
X1307500Y165961D03*
Y618717D03*
X1305100Y1071473D03*
X1354437Y81538D03*
X1337634Y130388D03*
X1421969Y517057D03*
X1413400Y567900D03*
X1431713Y165961D03*
X1470700Y525400D03*
X1435200Y518400D03*
X1448261Y518334D03*
X1456439Y518366D03*
X1447700Y572400D03*
X1474700D03*
X1431713Y618717D03*
Y1071473D03*
X1478700Y572400D03*
X1555925Y165961D03*
Y618717D03*
Y1071473D03*
X1585757Y126304D03*
X1602200Y1111200D03*
X1680138Y165961D03*
Y618717D03*
Y1071473D03*
X1804350Y165961D03*
Y618717D03*
X1774863Y1018025D03*
X1800750Y1071273D03*
X1855517Y161775D03*
X1843917Y193975D03*
X1855417Y614531D03*
X1843917Y646731D03*
X1840433Y1099941D03*
X1836431Y1144459D03*
X1868100Y1058800D03*
G54D81*
X1007010Y1521346D03*
Y1553748D03*
G54D36*
X111024Y141870D03*
Y314114D03*
Y594626D03*
Y766870D03*
Y1047382D03*
Y1219626D03*
X235236Y141870D03*
Y314114D03*
Y594626D03*
Y766870D03*
Y1047382D03*
Y1219626D03*
X359449Y141870D03*
Y314114D03*
Y594626D03*
Y766870D03*
Y1047382D03*
Y1219626D03*
X483661Y141870D03*
Y314114D03*
Y594626D03*
Y766870D03*
Y1047382D03*
Y1219626D03*
X607874Y141870D03*
Y314114D03*
Y594626D03*
Y766870D03*
Y1047382D03*
Y1219626D03*
X732087Y141870D03*
Y314114D03*
Y594626D03*
Y766870D03*
Y1047382D03*
Y1219626D03*
X938091Y-115157D03*
X1110335D03*
X1281693Y141870D03*
Y314114D03*
Y594626D03*
Y766870D03*
Y1047382D03*
Y1219626D03*
X1405906Y141870D03*
Y314114D03*
Y594626D03*
Y766870D03*
Y1047382D03*
Y1219626D03*
X1530118Y141870D03*
Y314114D03*
Y594626D03*
Y766870D03*
Y1047382D03*
Y1219626D03*
X1654331Y141870D03*
Y314114D03*
Y594626D03*
Y766870D03*
Y1047382D03*
Y1219626D03*
X1778543Y141870D03*
Y314114D03*
Y594626D03*
Y766870D03*
Y1047382D03*
Y1219626D03*
X1902756Y141870D03*
Y314114D03*
Y594626D03*
Y766870D03*
Y1047382D03*
Y1219626D03*
G54D27*
X68937Y254661D03*
X73437Y240161D03*
Y692917D03*
X68937Y707417D03*
Y1160173D03*
X73437Y1145673D03*
X79937Y254661D03*
X84437Y240161D03*
Y692917D03*
X79937Y707417D03*
Y1160173D03*
X84437Y1145673D03*
X204149Y254661D03*
X193149D03*
X197649Y240161D03*
X208649D03*
X197649Y692917D03*
X208649D03*
X193149Y707417D03*
X204149D03*
X193149Y1160173D03*
X204149D03*
X197649Y1145673D03*
X208649D03*
X328362Y254661D03*
X317362D03*
X321862Y240161D03*
X332862D03*
X321862Y692917D03*
X332862D03*
X317362Y707417D03*
X328362D03*
X317362Y1160173D03*
X328362D03*
X321862Y1145673D03*
X332862D03*
X452574Y254661D03*
X441574D03*
X446074Y240161D03*
X457074D03*
X446074Y692917D03*
X457074D03*
X441574Y707417D03*
X452574D03*
X456200Y1160200D03*
X467200D03*
X534874Y1145973D03*
X523874D03*
X576787Y254661D03*
X565787D03*
X570287Y240161D03*
X581287D03*
X570287Y692917D03*
X581287D03*
X565787Y707417D03*
X576787D03*
X565787Y1160173D03*
X576787D03*
X570287Y1145673D03*
X581287D03*
X701000Y254661D03*
X690000D03*
X694500Y240161D03*
Y692917D03*
X690000Y707417D03*
X701000D03*
X690000Y1160173D03*
X701000D03*
X694500Y1145673D03*
X705500Y240161D03*
Y692917D03*
Y1145673D03*
X1310500Y240661D03*
X1299500D03*
X1318775Y273366D03*
X1307775D03*
X1310500Y693417D03*
X1299500D03*
X1318834Y726182D03*
X1307834D03*
X1310500Y1146173D03*
X1299500D03*
X1318775Y1178761D03*
X1307775D03*
X1423713Y240661D03*
Y693417D03*
Y1146173D03*
X1434713Y240661D03*
X1443047Y273425D03*
X1432047D03*
X1434713Y693417D03*
X1443165Y726005D03*
X1432165D03*
X1442871Y1178820D03*
X1431871D03*
X1434713Y1146173D03*
X1558925Y240661D03*
X1547925D03*
X1567201Y273307D03*
X1556201D03*
X1558925Y693417D03*
X1547925D03*
X1567201Y726182D03*
X1556201D03*
X1558925Y1146173D03*
X1547925D03*
X1567259Y1179291D03*
X1556259D03*
X1683138Y240661D03*
X1672138D03*
X1691296Y273366D03*
X1680296D03*
X1683138Y693417D03*
X1672138D03*
X1691413Y726063D03*
X1680413D03*
X1683138Y1146173D03*
X1672138D03*
X1691590Y1178879D03*
X1680590D03*
X1807350Y240661D03*
X1796350D03*
X1804566Y273190D03*
X1807350Y693417D03*
X1796350D03*
X1806923Y725768D03*
X1807350Y1146173D03*
X1796350D03*
X1804743Y1178878D03*
X1860669Y254661D03*
X1815566Y273190D03*
X1817923Y725768D03*
X1857200Y707200D03*
X1815743Y1178878D03*
X1871669Y254661D03*
X1865169Y240161D03*
X1876169D03*
X1865169Y692917D03*
X1876169D03*
X1868200Y707200D03*
X1865548Y1126458D03*
X1876548D03*
X1875284Y1160157D03*
X1886284D03*
G54D72*
X883763Y829253D03*
X881203D03*
X878643D03*
X876083D03*
Y845553D03*
X878643D03*
X881203D03*
X883763D03*
X1037483Y861953D03*
X1040043D03*
Y845653D03*
X1037483D03*
X1042603Y861953D03*
X1045163D03*
Y845653D03*
X1042603D03*
G54D63*
X648392Y588186D03*
Y593186D03*
Y598186D03*
Y603186D03*
G54D45*
X139637Y256161D03*
Y708917D03*
Y1161673D03*
X263849Y256161D03*
Y708917D03*
Y1161673D03*
X388062Y256161D03*
Y708917D03*
X387862Y1161673D03*
X500074Y1130873D03*
X512274Y256161D03*
Y708917D03*
X525874Y1152773D03*
X636487Y256161D03*
Y708917D03*
Y1161673D03*
X827508Y37372D03*
X862777Y37234D03*
X932209Y991763D03*
X909282Y1534500D03*
X1107500Y-48400D03*
X1429400Y544600D03*
X1454461Y588256D03*
X1498082Y539100D03*
X1881532Y1054227D03*
G54D54*
X527145Y564270D03*
X525145Y558670D03*
X529145D03*
X899288Y1539560D03*
X897288Y1533960D03*
X901288D03*
X1100800Y-42800D03*
X1098800Y-48400D03*
X1102800D03*
G54D91*
G01X394744Y-485863D02*
X395618Y-484988D01*
X396273Y-483530D01*
X396710Y-481487D01*
X396273Y-479738D01*
X395400Y-478571D01*
X393871Y-477696D01*
X387976D01*
Y-495196D01*
X395181D01*
X396710Y-494030D01*
X397583Y-492279D01*
X398020Y-490238D01*
X397583Y-488196D01*
X396273Y-486446D01*
X394744Y-485863D01*
X387976D01*
G01X407441Y-495196D02*
Y-483530D01*
G01Y-485863D02*
X408533Y-484696D01*
X409625Y-483821D01*
X411153Y-483530D01*
X412244Y-483821D01*
X413555Y-484696D01*
G01X423413Y-500446D02*
X424723Y-501029D01*
X426470Y-500446D01*
X427561Y-499280D01*
X428435Y-497821D01*
X429744Y-493155D01*
X432583Y-483530D01*
G01X425596D02*
X429744Y-493155D01*
G01X448991Y-484988D02*
X447463Y-483821D01*
X446153Y-483530D01*
X444406Y-484113D01*
X443096Y-485279D01*
X442223Y-487321D01*
X442004Y-489363D01*
X442223Y-491405D01*
X443096Y-493155D01*
X444406Y-494613D01*
X446153Y-495196D01*
X447681Y-494613D01*
X448991Y-493446D01*
G01X459723Y-487321D02*
X466710D01*
X466055Y-485279D01*
X464963Y-484113D01*
X463435Y-483530D01*
X461906Y-483821D01*
X460596Y-484696D01*
X459723Y-486738D01*
X459286Y-488488D01*
Y-490238D01*
X459723Y-491988D01*
X460815Y-493738D01*
X462125Y-494904D01*
X463653Y-495196D01*
X465181Y-494613D01*
X466710Y-492863D01*
G01X502801Y-479155D02*
X501491Y-478279D01*
X499963Y-477696D01*
X498216D01*
X496251Y-478571D01*
X494723Y-480029D01*
X493631Y-481780D01*
X492758Y-484696D01*
X492539Y-487321D01*
X492976Y-489946D01*
X493631Y-491696D01*
X494941Y-493446D01*
X496470Y-494613D01*
X497998Y-495196D01*
X499526D01*
X501055Y-494613D01*
X502365Y-493738D01*
X503457Y-492572D01*
G01X519428Y-495196D02*
Y-483530D01*
G01Y-485571D02*
X518555Y-484405D01*
X517244Y-483821D01*
X515716Y-483530D01*
X514188Y-484113D01*
X512878Y-485279D01*
X512004Y-487029D01*
X511568Y-489363D01*
X512004Y-491696D01*
X512878Y-493446D01*
X514188Y-494613D01*
X515716Y-495196D01*
X517244Y-494904D01*
X518555Y-494030D01*
X519428Y-492863D01*
G01X529286Y-495196D02*
Y-483530D01*
G01Y-486446D02*
X530160Y-484988D01*
X531470Y-483821D01*
X533216Y-483530D01*
X534744Y-483821D01*
X536055Y-484988D01*
X536710Y-487029D01*
Y-495196D01*
G01X545913Y-500446D02*
X547223Y-501029D01*
X548970Y-500446D01*
X550061Y-499280D01*
X550935Y-497821D01*
X552244Y-493155D01*
X555083Y-483530D01*
G01X548096D02*
X552244Y-493155D01*
G01X567998Y-495196D02*
X566688Y-494904D01*
X565378Y-493738D01*
X564504Y-491696D01*
X564068Y-489363D01*
X564504Y-487029D01*
X565378Y-484988D01*
X566688Y-483821D01*
X567998Y-483530D01*
X569308Y-483821D01*
X570618Y-484988D01*
X571491Y-487029D01*
X571710Y-489363D01*
X571491Y-491696D01*
X570618Y-493738D01*
X569308Y-494904D01*
X567998Y-495196D01*
G01X581786D02*
Y-483530D01*
G01Y-486446D02*
X582660Y-484988D01*
X583970Y-483821D01*
X585716Y-483530D01*
X587244Y-483821D01*
X588555Y-484988D01*
X589210Y-487029D01*
Y-495196D01*
G01X616350D02*
Y-477696D01*
X624646D01*
G01X621590Y-486154D02*
X616350D01*
G01X637998Y-495779D02*
X637561Y-495488D01*
Y-494904D01*
X637998Y-494613D01*
X638435Y-494904D01*
Y-495488D01*
X637998Y-495779D01*
G01X650695Y-495196D02*
Y-477696D01*
X655061D01*
X656808Y-478571D01*
X658118Y-479738D01*
X659210Y-481487D01*
X660083Y-483530D01*
X660301Y-486446D01*
X660083Y-489363D01*
X659210Y-491405D01*
X658118Y-493155D01*
X656808Y-494321D01*
X655061Y-495196D01*
X650695D01*
G01X668631D02*
Y-477696D01*
X673871D01*
X675618Y-478571D01*
X676928Y-480613D01*
X677365Y-482946D01*
X676928Y-485279D01*
X675836Y-487029D01*
X673871Y-487905D01*
X668631D01*
G01X692244Y-485863D02*
X693118Y-484988D01*
X693773Y-483530D01*
X694210Y-481487D01*
X693773Y-479738D01*
X692900Y-478571D01*
X691371Y-477696D01*
X685476D01*
Y-495196D01*
X692681D01*
X694210Y-494030D01*
X695083Y-492279D01*
X695520Y-490238D01*
X695083Y-488196D01*
X693773Y-486446D01*
X692244Y-485863D01*
X685476D01*
G01X501071Y-450196D02*
Y-432696D01*
X506748Y-447279D01*
X512425Y-432696D01*
Y-450196D01*
G01X524248D02*
X522938Y-449904D01*
X521628Y-448738D01*
X520754Y-446696D01*
X520318Y-444363D01*
X520754Y-442029D01*
X521628Y-439988D01*
X522938Y-438821D01*
X524248Y-438530D01*
X525558Y-438821D01*
X526868Y-439988D01*
X527741Y-442029D01*
X527960Y-444363D01*
X527741Y-446696D01*
X526868Y-448738D01*
X525558Y-449904D01*
X524248Y-450196D01*
G01X545678Y-432696D02*
Y-450196D01*
G01Y-447572D02*
X544805Y-449030D01*
X543494Y-449904D01*
X541966Y-450196D01*
X540220Y-449613D01*
X538910Y-448155D01*
X538036Y-446405D01*
X537818Y-444363D01*
X538036Y-442321D01*
X538910Y-440571D01*
X540220Y-439113D01*
X541966Y-438530D01*
X543494Y-438821D01*
X544586Y-439405D01*
X545678Y-440571D01*
G01X555973Y-442321D02*
X562960D01*
X562305Y-440279D01*
X561213Y-439113D01*
X559685Y-438530D01*
X558156Y-438821D01*
X556846Y-439696D01*
X555973Y-441738D01*
X555536Y-443488D01*
Y-445238D01*
X555973Y-446988D01*
X557065Y-448738D01*
X558375Y-449904D01*
X559903Y-450196D01*
X561431Y-449613D01*
X562960Y-447863D01*
G01X576748Y-450196D02*
Y-432696D01*
G01X754448Y-495196D02*
Y-477696D01*
X751828Y-481196D01*
G01Y-495196D02*
X757068D01*
G01X767800Y-487905D02*
X769328Y-485863D01*
X770638Y-484696D01*
X772385Y-484113D01*
X773913Y-484696D01*
X775005Y-485863D01*
X775878Y-487613D01*
X776096Y-489654D01*
X775878Y-491405D01*
X775005Y-493155D01*
X773694Y-494613D01*
X772166Y-495196D01*
X770420Y-494613D01*
X768891Y-492863D01*
X768018Y-490238D01*
X767800Y-487321D01*
X768236Y-483530D01*
X768891Y-481487D01*
X769983Y-479446D01*
X771511Y-477988D01*
X773040Y-477696D01*
X774568Y-478279D01*
X775660Y-479738D01*
G01X784645Y-491696D02*
X785954Y-493738D01*
X787701Y-494904D01*
X789666Y-495196D01*
X791413Y-494904D01*
X793160Y-493446D01*
X794251Y-491696D01*
X794470Y-489946D01*
X794033Y-487905D01*
X792505Y-486446D01*
X790976Y-485863D01*
X789011D01*
G01X790976D02*
X792286Y-484988D01*
X793378Y-483530D01*
X793815Y-481780D01*
X793378Y-480029D01*
X792286Y-478571D01*
X790321Y-477696D01*
X788356Y-477988D01*
X786391Y-479155D01*
G01X806948Y-495196D02*
Y-477696D01*
X804328Y-481196D01*
G01Y-495196D02*
X809568D01*
G01X819645Y-492572D02*
X820954Y-494030D01*
X822483Y-494904D01*
X824448Y-495196D01*
X826413Y-494613D01*
X827941Y-493446D01*
X829033Y-491405D01*
X829251Y-489071D01*
X828815Y-486738D01*
X827723Y-485279D01*
X826194Y-484113D01*
X824666Y-483821D01*
X823138Y-484113D01*
X821173Y-485279D01*
X821828Y-477696D01*
X827723D01*
G01X741331Y-450196D02*
Y-432696D01*
X746571D01*
X748318Y-433571D01*
X749628Y-435613D01*
X750065Y-437946D01*
X749628Y-440279D01*
X748536Y-442029D01*
X746571Y-442905D01*
X741331D01*
G01X768001Y-434155D02*
X766691Y-433279D01*
X765163Y-432696D01*
X763416D01*
X761451Y-433571D01*
X759923Y-435029D01*
X758831Y-436780D01*
X757958Y-439696D01*
X757739Y-442321D01*
X758176Y-444946D01*
X758831Y-446696D01*
X760141Y-448446D01*
X761670Y-449613D01*
X763198Y-450196D01*
X764726D01*
X766255Y-449613D01*
X767565Y-448738D01*
X768657Y-447572D01*
G01X782444Y-440863D02*
X783318Y-439988D01*
X783973Y-438530D01*
X784410Y-436487D01*
X783973Y-434738D01*
X783100Y-433571D01*
X781571Y-432696D01*
X775676D01*
Y-450196D01*
X782881D01*
X784410Y-449030D01*
X785283Y-447279D01*
X785720Y-445238D01*
X785283Y-443196D01*
X783973Y-441446D01*
X782444Y-440863D01*
X775676D01*
G01X791648Y-456029D02*
X804748D01*
G01X810676Y-450196D02*
Y-432696D01*
X820720Y-450196D01*
Y-432696D01*
G01X833198Y-450196D02*
X831451Y-449904D01*
X829923Y-448738D01*
X828613Y-446988D01*
X827739Y-444946D01*
X827303Y-442613D01*
Y-440279D01*
X827739Y-437946D01*
X828613Y-435904D01*
X829923Y-434155D01*
X831451Y-432988D01*
X833198Y-432696D01*
X834944Y-432988D01*
X836473Y-434155D01*
X837783Y-435904D01*
X838657Y-437946D01*
X839093Y-440279D01*
Y-442613D01*
X838657Y-444946D01*
X837783Y-446988D01*
X836473Y-448738D01*
X834944Y-449904D01*
X833198Y-450196D01*
G01X884039Y-432696D02*
X889498Y-450196D01*
X894957Y-432696D01*
G01X911365Y-450196D02*
X902631D01*
Y-432696D01*
X911365D01*
G01X907871Y-441154D02*
X902631D01*
G01X920131Y-450196D02*
Y-432696D01*
X925590D01*
X927336Y-433571D01*
X928428Y-434738D01*
X928865Y-437071D01*
X928428Y-439405D01*
X927118Y-440863D01*
X925590Y-441738D01*
X920131D01*
G01X925590D02*
X928865Y-450196D01*
G01X941998Y-450779D02*
X941561Y-450488D01*
Y-449904D01*
X941998Y-449613D01*
X942435Y-449904D01*
Y-450488D01*
X941998Y-450779D01*
G01X915748Y-495196D02*
Y-477696D01*
X913128Y-481196D01*
G01Y-495196D02*
X918368D01*
G01X1082981Y-432696D02*
Y-450196D01*
X1091715D01*
G01X1108778D02*
Y-438530D01*
G01Y-440571D02*
X1107905Y-439405D01*
X1106594Y-438821D01*
X1105066Y-438530D01*
X1103538Y-439113D01*
X1102228Y-440279D01*
X1101354Y-442029D01*
X1100918Y-444363D01*
X1101354Y-446696D01*
X1102228Y-448446D01*
X1103538Y-449613D01*
X1105066Y-450196D01*
X1106594Y-449904D01*
X1107905Y-449030D01*
X1108778Y-447863D01*
G01X1117763Y-455446D02*
X1119073Y-456029D01*
X1120820Y-455446D01*
X1121911Y-454280D01*
X1122785Y-452821D01*
X1124094Y-448155D01*
X1126933Y-438530D01*
G01X1119946D02*
X1124094Y-448155D01*
G01X1136573Y-442321D02*
X1143560D01*
X1142905Y-440279D01*
X1141813Y-439113D01*
X1140285Y-438530D01*
X1138756Y-438821D01*
X1137446Y-439696D01*
X1136573Y-441738D01*
X1136136Y-443488D01*
Y-445238D01*
X1136573Y-446988D01*
X1137665Y-448738D01*
X1138975Y-449904D01*
X1140503Y-450196D01*
X1142031Y-449613D01*
X1143560Y-447863D01*
G01X1154291Y-450196D02*
Y-438530D01*
G01Y-440863D02*
X1155383Y-439696D01*
X1156475Y-438821D01*
X1158003Y-438530D01*
X1159094Y-438821D01*
X1160405Y-439696D01*
G01X1096098Y-477696D02*
Y-495196D01*
G01X1091076Y-477696D02*
X1101120D01*
G01X1109013Y-492863D02*
X1110760Y-494321D01*
X1112725Y-495196D01*
X1114471D01*
X1116218Y-494321D01*
X1117528Y-492863D01*
X1118183Y-490821D01*
X1117746Y-488780D01*
X1116655Y-487029D01*
X1114690Y-485863D01*
X1112070Y-485279D01*
X1110541Y-484113D01*
X1109886Y-482071D01*
X1110323Y-480029D01*
X1111415Y-478571D01*
X1112943Y-477696D01*
X1114471D01*
X1116000Y-478279D01*
X1117310Y-479738D01*
G01X1125421Y-495196D02*
Y-477696D01*
X1131098Y-492279D01*
X1136775Y-477696D01*
Y-495196D01*
G01X1143795D02*
Y-477696D01*
X1148161D01*
X1149908Y-478571D01*
X1151218Y-479738D01*
X1152310Y-481487D01*
X1153183Y-483530D01*
X1153401Y-486446D01*
X1153183Y-489363D01*
X1152310Y-491405D01*
X1151218Y-493155D01*
X1149908Y-494321D01*
X1148161Y-495196D01*
X1143795D01*
G01X1312898D02*
X1311151Y-494904D01*
X1309623Y-493738D01*
X1308313Y-491988D01*
X1307439Y-489946D01*
X1307003Y-487613D01*
Y-485279D01*
X1307439Y-482946D01*
X1308313Y-480904D01*
X1309623Y-479155D01*
X1311151Y-477988D01*
X1312898Y-477696D01*
X1314644Y-477988D01*
X1316173Y-479155D01*
X1317483Y-480904D01*
X1318357Y-482946D01*
X1318793Y-485279D01*
Y-487613D01*
X1318357Y-489946D01*
X1317483Y-491988D01*
X1316173Y-493738D01*
X1314644Y-494904D01*
X1312898Y-495196D01*
G01X1314644Y-490529D02*
X1317265Y-495196D01*
G01X1325595Y-477696D02*
Y-490238D01*
X1326468Y-492863D01*
X1328215Y-494613D01*
X1330398Y-495196D01*
X1332581Y-494613D01*
X1334328Y-492863D01*
X1335201Y-490238D01*
Y-477696D01*
G01X1345278D02*
X1350518D01*
G01X1347898D02*
Y-495196D01*
G01X1345278D02*
X1350518D01*
G01X1360376D02*
Y-477696D01*
X1370420Y-495196D01*
Y-477696D01*
G01X1387701Y-479155D02*
X1386391Y-478279D01*
X1384863Y-477696D01*
X1383116D01*
X1381151Y-478571D01*
X1379623Y-480029D01*
X1378531Y-481780D01*
X1377658Y-484696D01*
X1377439Y-487321D01*
X1377876Y-489946D01*
X1378531Y-491696D01*
X1379841Y-493446D01*
X1381370Y-494613D01*
X1382898Y-495196D01*
X1384426D01*
X1385955Y-494613D01*
X1387265Y-493738D01*
X1388357Y-492572D01*
G01X1400398Y-495196D02*
Y-487321D01*
X1396031Y-477696D01*
G01X1404765D02*
X1400398Y-487321D01*
G01X1290595Y-450196D02*
Y-432696D01*
X1294961D01*
X1296708Y-433571D01*
X1298018Y-434738D01*
X1299110Y-436487D01*
X1299983Y-438530D01*
X1300201Y-441446D01*
X1299983Y-444363D01*
X1299110Y-446405D01*
X1298018Y-448155D01*
X1296708Y-449321D01*
X1294961Y-450196D01*
X1290595D01*
G01X1309623Y-442321D02*
X1316610D01*
X1315955Y-440279D01*
X1314863Y-439113D01*
X1313335Y-438530D01*
X1311806Y-438821D01*
X1310496Y-439696D01*
X1309623Y-441738D01*
X1309186Y-443488D01*
Y-445238D01*
X1309623Y-446988D01*
X1310715Y-448738D01*
X1312025Y-449904D01*
X1313553Y-450196D01*
X1315081Y-449613D01*
X1316610Y-447863D01*
G01X1327123Y-448155D02*
X1328215Y-449321D01*
X1329743Y-450196D01*
X1331053D01*
X1332363Y-449613D01*
X1333236Y-448738D01*
X1333673Y-447572D01*
X1333455Y-445821D01*
X1332581Y-444946D01*
X1328651Y-443196D01*
X1327778Y-441154D01*
X1328215Y-439696D01*
X1329088Y-438821D01*
X1330398Y-438530D01*
X1331708Y-438821D01*
X1333018Y-439696D01*
G01X1347898Y-438530D02*
Y-450196D01*
G01Y-433863D02*
X1347461Y-433571D01*
Y-432988D01*
X1347898Y-432696D01*
X1348335Y-432988D01*
Y-433571D01*
X1347898Y-433863D01*
G01X1362341Y-454571D02*
X1363870Y-455738D01*
X1365616Y-456029D01*
X1367144Y-455738D01*
X1368455Y-454280D01*
X1369328Y-452238D01*
Y-438530D01*
G01Y-440863D02*
X1368455Y-439696D01*
X1367144Y-438821D01*
X1365616Y-438530D01*
X1363870Y-439113D01*
X1362778Y-440279D01*
X1361904Y-442321D01*
X1361468Y-444363D01*
X1361686Y-446113D01*
X1362560Y-448155D01*
X1363870Y-449613D01*
X1365616Y-450196D01*
X1366926Y-449904D01*
X1368455Y-448738D01*
X1369328Y-447572D01*
G01X1379186Y-450196D02*
Y-438530D01*
G01Y-441446D02*
X1380060Y-439988D01*
X1381370Y-438821D01*
X1383116Y-438530D01*
X1384644Y-438821D01*
X1385955Y-439988D01*
X1386610Y-442029D01*
Y-450196D01*
G01X1397123Y-442321D02*
X1404110D01*
X1403455Y-440279D01*
X1402363Y-439113D01*
X1400835Y-438530D01*
X1399306Y-438821D01*
X1397996Y-439696D01*
X1397123Y-441738D01*
X1396686Y-443488D01*
Y-445238D01*
X1397123Y-446988D01*
X1398215Y-448738D01*
X1399525Y-449904D01*
X1401053Y-450196D01*
X1402581Y-449613D01*
X1404110Y-447863D01*
G01X1414841Y-450196D02*
Y-438530D01*
G01Y-440863D02*
X1415933Y-439696D01*
X1417025Y-438821D01*
X1418553Y-438530D01*
X1419644Y-438821D01*
X1420955Y-439696D01*
G01X1461598Y-477696D02*
X1459851Y-478279D01*
X1458541Y-479738D01*
X1457668Y-481487D01*
X1457013Y-483821D01*
X1456795Y-486446D01*
X1457013Y-489071D01*
X1457668Y-491405D01*
X1458541Y-493155D01*
X1459851Y-494613D01*
X1461598Y-495196D01*
X1463344Y-494613D01*
X1464655Y-493155D01*
X1465528Y-491405D01*
X1466183Y-489071D01*
X1466401Y-486446D01*
X1466183Y-483821D01*
X1465528Y-481487D01*
X1464655Y-479738D01*
X1463344Y-478279D01*
X1461598Y-477696D01*
G01X1474950Y-487905D02*
X1476478Y-485863D01*
X1477788Y-484696D01*
X1479535Y-484113D01*
X1481063Y-484696D01*
X1482155Y-485863D01*
X1483028Y-487613D01*
X1483246Y-489654D01*
X1483028Y-491405D01*
X1482155Y-493155D01*
X1480844Y-494613D01*
X1479316Y-495196D01*
X1477570Y-494613D01*
X1476041Y-492863D01*
X1475168Y-490238D01*
X1474950Y-487321D01*
X1475386Y-483530D01*
X1476041Y-481487D01*
X1477133Y-479446D01*
X1478661Y-477988D01*
X1480190Y-477696D01*
X1481718Y-478279D01*
X1482810Y-479738D01*
G01X1492668Y-495779D02*
X1500528Y-477696D01*
G01X1514098D02*
X1512351Y-478279D01*
X1511041Y-479738D01*
X1510168Y-481487D01*
X1509513Y-483821D01*
X1509295Y-486446D01*
X1509513Y-489071D01*
X1510168Y-491405D01*
X1511041Y-493155D01*
X1512351Y-494613D01*
X1514098Y-495196D01*
X1515844Y-494613D01*
X1517155Y-493155D01*
X1518028Y-491405D01*
X1518683Y-489071D01*
X1518901Y-486446D01*
X1518683Y-483821D01*
X1518028Y-481487D01*
X1517155Y-479738D01*
X1515844Y-478279D01*
X1514098Y-477696D01*
G01X1527886Y-493155D02*
X1529415Y-494613D01*
X1531161Y-495196D01*
X1532908Y-494613D01*
X1534436Y-492863D01*
X1535528Y-490238D01*
X1535965Y-487613D01*
Y-484405D01*
X1535528Y-481780D01*
X1534436Y-479446D01*
X1533126Y-478279D01*
X1531598Y-477696D01*
X1529851Y-478279D01*
X1528541Y-479446D01*
X1527668Y-481196D01*
X1527231Y-483530D01*
X1527668Y-485571D01*
X1528760Y-487613D01*
X1530070Y-488780D01*
X1531598Y-489071D01*
X1533344Y-488488D01*
X1534655Y-487029D01*
X1535965Y-484405D01*
G01X1545168Y-495779D02*
X1553028Y-477696D01*
G01X1562450Y-480613D02*
X1563760Y-478863D01*
X1565288Y-477988D01*
X1567035Y-477696D01*
X1569218Y-478279D01*
X1570746Y-479738D01*
X1571183Y-481487D01*
X1570965Y-483238D01*
X1570091Y-484696D01*
X1565725Y-487613D01*
X1563760Y-489654D01*
X1562450Y-492572D01*
X1562013Y-495196D01*
X1571183D01*
G01X1584098Y-477696D02*
X1582351Y-478279D01*
X1581041Y-479738D01*
X1580168Y-481487D01*
X1579513Y-483821D01*
X1579295Y-486446D01*
X1579513Y-489071D01*
X1580168Y-491405D01*
X1581041Y-493155D01*
X1582351Y-494613D01*
X1584098Y-495196D01*
X1585844Y-494613D01*
X1587155Y-493155D01*
X1588028Y-491405D01*
X1588683Y-489071D01*
X1588901Y-486446D01*
X1588683Y-483821D01*
X1588028Y-481487D01*
X1587155Y-479738D01*
X1585844Y-478279D01*
X1584098Y-477696D01*
G01X1601598Y-495196D02*
Y-477696D01*
X1598978Y-481196D01*
G01Y-495196D02*
X1604218D01*
G01X1618661D02*
X1619098Y-491405D01*
X1619753Y-488196D01*
X1620626Y-485279D01*
X1621718Y-482071D01*
X1623465Y-477696D01*
X1614731D01*
G01X1509295Y-450196D02*
Y-432696D01*
X1513661D01*
X1515408Y-433571D01*
X1516718Y-434738D01*
X1517810Y-436487D01*
X1518683Y-438530D01*
X1518901Y-441446D01*
X1518683Y-444363D01*
X1517810Y-446405D01*
X1516718Y-448155D01*
X1515408Y-449321D01*
X1513661Y-450196D01*
X1509295D01*
G01X1535528D02*
Y-438530D01*
G01Y-440571D02*
X1534655Y-439405D01*
X1533344Y-438821D01*
X1531816Y-438530D01*
X1530288Y-439113D01*
X1528978Y-440279D01*
X1528104Y-442029D01*
X1527668Y-444363D01*
X1528104Y-446696D01*
X1528978Y-448446D01*
X1530288Y-449613D01*
X1531816Y-450196D01*
X1533344Y-449904D01*
X1534655Y-449030D01*
X1535528Y-447863D01*
G01X1549098Y-432696D02*
Y-450196D01*
G01X1546041Y-438530D02*
X1552155D01*
G01X1563323Y-442321D02*
X1570310D01*
X1569655Y-440279D01*
X1568563Y-439113D01*
X1567035Y-438530D01*
X1565506Y-438821D01*
X1564196Y-439696D01*
X1563323Y-441738D01*
X1562886Y-443488D01*
Y-445238D01*
X1563323Y-446988D01*
X1564415Y-448738D01*
X1565725Y-449904D01*
X1567253Y-450196D01*
X1568781Y-449613D01*
X1570310Y-447863D01*
G01X0Y-137756D02*
G03X15000Y-152756I15000J0D01*
G01X0Y-137756D02*
G03X15000Y-152756I15000J0D01*
G01X0Y-11811D02*
Y-137756D01*
G01Y-11811D02*
Y-137756D01*
G01X854331Y-152756D02*
X15000D01*
G01X854331D02*
X15000D01*
G01X23622Y-7874D02*
G03Y0I0J3937D01*
G01Y-7874D02*
G03Y0I0J3937D01*
G01X0Y3937D02*
G03X3937Y0I3937J0D01*
G01Y-7874D02*
X23622D01*
G01X0Y3937D02*
G03X3937Y0I3937J0D01*
G01Y-7874D02*
X23622D01*
G01X3937D02*
G03X0Y-11811I0J-3937D01*
G01X3937Y-7874D02*
G03X0Y-11811I0J-3937D01*
G01X3937Y0D02*
X397638D01*
G01X3937D02*
X397638D01*
G01X0Y1370866D02*
Y3937D01*
G01Y1370866D02*
Y3937D01*
G01X3937Y1374803D02*
G03X0Y1370866I0J-3937D01*
G01X3937Y1374803D02*
G03X0Y1370866I0J-3937D01*
G01X23622Y1374803D02*
G03Y1382677I0J3937D01*
G01Y1374803D02*
G03Y1382677I0J3937D01*
G01X3937D02*
X23622D01*
G01X0Y1386614D02*
G03X3937Y1382677I3937J0D01*
G01D02*
X23622D01*
G01X0Y1386614D02*
G03X3937Y1382677I3937J0D01*
G01Y1374803D02*
X746850D01*
G01D02*
X3937D01*
G01X0Y1386614D02*
Y1643268D01*
G01Y1386614D02*
Y1643268D01*
G01X15000Y1658268D02*
G03X0Y1643268I0J-15000D01*
G01X15000Y1658268D02*
G03X0Y1643268I0J-15000D01*
G01X775591Y1658268D02*
X15000D01*
G01X775591D02*
X15000D01*
G01X54331Y-7874D02*
X323228D01*
G01X54331D02*
X323228D01*
G01X54331Y0D02*
G03Y-7874I0J-3937D01*
G01Y0D02*
G03Y-7874I0J-3937D01*
G01Y1382677D02*
G03Y1374803I0J-3937D01*
G01Y1382677D02*
G03Y1374803I0J-3937D01*
G01Y1382677D02*
X353740D01*
G01X54331D02*
X353740D01*
G01X114295Y378885D02*
G03X148106I16905J-13531D01*
G01X114295D02*
G03X148106I16905J-13531D01*
G01X114295D02*
G03X121220Y392016I-30737J24602D01*
G01X114295Y378885D02*
G03X121220Y392016I-30737J24602D01*
G01X114295Y831641D02*
G03X121220Y844772I-30737J24601D01*
G01X114295Y831641D02*
G03X121220Y844772I-30737J24602D01*
G01X114295Y831641D02*
G03X148106I16905J-13531D01*
G01X114295D02*
G03X148106I16905J-13531D01*
G01X114295Y1284397D02*
G03X148106I16905J-13531D01*
G01X114295D02*
G03X148106I16905J-13531D01*
G01X114295D02*
G03X121220Y1297528I-30737J24601D01*
G01X114295Y1284397D02*
G03X121220Y1297528I-30737J24602D01*
G01X141181Y392016D02*
G03X121220I-9980J-3039D01*
G01X141181D02*
G03X148106Y378885I37662J11471D01*
G01X141181Y392016D02*
G03X121220I-9980J-3039D01*
G01X141181D02*
G03X148106Y378885I37662J11471D01*
G01X141181Y844772D02*
G03X148106Y831641I37662J11471D01*
G01X141181Y844772D02*
G03X148106Y831641I37662J11471D01*
G01X141181Y844772D02*
G03X121220I-9980J-3040D01*
G01X141181D02*
G03X121220I-9980J-3039D01*
G01X141181Y1297528D02*
G03X121220I-9980J-3040D01*
G01X141181D02*
G03X148106Y1284397I37662J11471D01*
G01X141181Y1297528D02*
G03X121220I-9980J-3040D01*
G01X141181D02*
G03X148106Y1284397I37662J11471D01*
G01X323228Y-7874D02*
G03Y0I0J3937D01*
G01Y-7874D02*
G03Y0I0J3937D01*
G01X362598D02*
G03Y-7874I0J-3937D01*
G01Y0D02*
G03Y-7874I0J-3937D01*
G01X362327Y378885D02*
G03X396138I16905J-13531D01*
G01X362327D02*
G03X396138I16905J-13531D01*
G01X362327D02*
G03X369252Y392016I-30737J24602D01*
G01X362327Y378885D02*
G03X369252Y392016I-30737J24602D01*
G01X362327Y831641D02*
G03X369252Y844772I-30737J24602D01*
G01X362327Y831641D02*
G03X369252Y844772I-30737J24602D01*
G01X362327Y831641D02*
G03X396138I16905J-13531D01*
G01X362327D02*
G03X396138I16905J-13531D01*
G01X362327Y1284397D02*
G03X396138I16905J-13531D01*
G01X362327D02*
G03X396138I16905J-13531D01*
G01X362327D02*
G03X369252Y1297528I-30737J24602D01*
G01X362327Y1284397D02*
G03X369252Y1297528I-30737J24602D01*
G01X353740Y1374803D02*
G03Y1382677I0J3937D01*
G01Y1374803D02*
G03Y1382677I0J3937D01*
G01X401575Y3937D02*
Y55118D01*
G01X397638Y0D02*
G03X401575Y3937I0J3937D01*
G01X409449D02*
Y51181D01*
G01X397638Y-7874D02*
G03X409449Y3937I0J11811D01*
G01X397638Y0D02*
G03X401575Y3937I0J3937D01*
G01D02*
Y55118D01*
G01X409449Y3937D02*
Y51181D01*
G01X397638Y-7874D02*
G03X409449Y3937I0J11811D01*
G01X362598Y-7874D02*
X397638D01*
G01X362598D02*
X397638D01*
G01X405512Y59055D02*
G03X401575Y55118I0J-3937D01*
G01X405512Y59055D02*
G03X401575Y55118I0J-3937D01*
G01X405512Y59055D02*
X586614D01*
G01X409449Y51181D02*
X582677D01*
G01X405512Y59055D02*
X586614D01*
G01X409449Y51181D02*
X582677D01*
G01X389213Y392016D02*
G03X396138Y378885I37662J11471D01*
G01X389213Y392016D02*
G03X396138Y378885I37662J11471D01*
G01X389213Y392016D02*
G03X369252I-9981J-3039D01*
G01X389213D02*
G03X369252I-9981J-3039D01*
G01X389213Y844772D02*
G03X396138Y831641I37662J11471D01*
G01X389213Y844772D02*
G03X396138Y831641I37662J11471D01*
G01X389213Y844772D02*
G03X369252I-9981J-3040D01*
G01X389213D02*
G03X369252I-9981J-3039D01*
G01X389213Y1297528D02*
G03X396138Y1284397I37662J11471D01*
G01X389213Y1297528D02*
G03X396138Y1284397I37662J11471D01*
G01X389213Y1297528D02*
G03X369252I-9981J-3040D01*
G01X389213D02*
G03X369252I-9981J-3040D01*
G01X393110Y1382677D02*
G03Y1374803I0J-3937D01*
G01Y1382677D02*
X692520D01*
G01X393110D02*
X692520D01*
G01X393110D02*
G03Y1374803I0J-3937D01*
G01X523327Y829921D02*
G03X483169I-20079J0D01*
G01X523327D02*
G03I-20079J0D01*
G01X483169D02*
G03X523327I20079J0D01*
G01X594488Y-7874D02*
X628765D01*
G01X594488D02*
X628765D01*
G01X590551Y55118D02*
Y3937D01*
G01D02*
G03X594488Y0I3937J0D01*
G01X582677Y51181D02*
Y3937D01*
G01D02*
G03X594488Y-7874I11811J0D01*
G01X590551Y55118D02*
Y3937D01*
G01D02*
G03X594488Y0I3937J0D01*
G01X582677Y51181D02*
Y3937D01*
G01D02*
G03X594488Y-7874I11811J0D01*
G01Y0D02*
X783465D01*
G01X594488D02*
X783465D01*
G01X590551Y55118D02*
G03X586614Y59055I-3937J0D01*
G01X590551Y55118D02*
G03X586614Y59055I-3937J0D01*
G01X628765Y-7874D02*
G03Y0I0J3937D01*
G01Y-7874D02*
G03Y0I0J3937D01*
G01X610358Y378885D02*
G03X644169I16906J-13531D01*
G01X610358D02*
G03X644169I16906J-13531D01*
G01X637244Y392016D02*
G03X644169Y378885I37662J11471D01*
G01X637244Y392016D02*
G03X644169Y378885I37662J11471D01*
G01X637244Y392016D02*
G03X617283I-9980J-3039D01*
G01X637244D02*
G03X617283I-9980J-3039D01*
G01X610358Y378885D02*
G03X617283Y392016I-30737J24602D01*
G01X610358Y378885D02*
G03X617283Y392016I-30737J24602D01*
G01X637244Y844772D02*
G03X644169Y831641I37662J11471D01*
G01X637244Y844772D02*
G03X644169Y831641I37662J11471D01*
G01X610358D02*
G03X617283Y844772I-30737J24601D01*
G01X610358Y831641D02*
G03X617283Y844772I-30737J24602D01*
G01X610358Y831641D02*
G03X644169I16906J-13531D01*
G01X610358D02*
G03X644169I16906J-13531D01*
G01X637244Y844772D02*
G03X617283I-9980J-3040D01*
G01X637244D02*
G03X617283I-9980J-3039D01*
G01X610358Y1284397D02*
G03X644169I16906J-13531D01*
G01X610358D02*
G03X644169I16906J-13531D01*
G01X637244Y1297528D02*
G03X644169Y1284397I37662J11471D01*
G01X637244Y1297528D02*
G03X644169Y1284397I37662J11471D01*
G01X610358D02*
G03X617283Y1297528I-30737J24601D01*
G01X637244D02*
G03X617283I-9980J-3040D01*
G01X610358Y1284397D02*
G03X617283Y1297528I-30737J24602D01*
G01X637244D02*
G03X617283I-9980J-3040D01*
G01X659474Y0D02*
G03Y-7874I0J-3937D01*
G01Y0D02*
G03Y-7874I0J-3937D01*
G01D02*
X780203D01*
G01X659474D02*
X780203D01*
G01X692520Y1374803D02*
G03Y1382677I0J3937D01*
G01Y1374803D02*
G03Y1382677I0J3937D01*
G01X746850Y1374803D02*
G03X750787Y1378740I0J3937D01*
G01X746850Y1374803D02*
G03X750787Y1378740I0J3937D01*
G01X723228Y1382677D02*
G03Y1374803I0J-3937D01*
G01Y1382677D02*
X742913D01*
G01X723228D02*
X742913D01*
G01X723228D02*
G03Y1374803I0J-3937D01*
G01X742913Y1464567D02*
Y1382677D01*
G01Y1464567D02*
Y1382677D01*
G01X754724Y1476378D02*
G03X742913Y1464567I0J-11811D01*
G01X754724Y1476378D02*
G03X742913Y1464567I0J-11811D01*
G01X862205Y-7874D02*
X791339D01*
G01X787402Y-3937D02*
G03X791339Y-7874I3937J0D01*
G01X787402Y-3937D02*
G03X791339Y-7874I3937J0D01*
G01D02*
X862205D01*
G01X858268Y-15748D02*
X791339D01*
G01X858268D02*
X791339D01*
G01X787402Y-3937D02*
G03X783465Y0I-3937J0D01*
G01X787402Y-3937D02*
G03X783465Y0I-3937J0D01*
G01X780203Y-7874D02*
G03X791339Y-15748I11136J3937D01*
G01X780203Y-7874D02*
G03X791339Y-15748I11136J3937D01*
G01X779551Y264712D02*
G03X813362I16905J-13531D01*
G01X779551D02*
G03X813362I16905J-13531D01*
G01X779551D02*
G03X786476Y277843I-30737J24601D01*
G01X806437D02*
G03X786476I-9981J-3040D01*
G01X779551Y264712D02*
G03X786476Y277843I-30737J24602D01*
G01X806437D02*
G03X786476I-9981J-3040D01*
G01X779551Y737153D02*
G03X786476Y750284I-30737J24601D01*
G01X779551Y737154D02*
G03X786476Y750284I-30736J24602D01*
G01X779551Y737153D02*
G03X813362I16905J-13531D01*
G01X779551D02*
G03X813362I16905J-13531D01*
G01X806437Y750284D02*
G03X786476I-9981J-3040D01*
G01X806437D02*
G03X786476I-9981J-3040D01*
G01X750787Y1464567D02*
Y1378740D01*
G01Y1464567D02*
Y1378740D01*
G01X783465Y1468504D02*
G03X787402Y1472441I0J3937D01*
G01X783465Y1468504D02*
G03X787402Y1472441I0J3937D01*
G01X783465Y1468504D02*
X754724D01*
G01D02*
G03X750787Y1464567I0J-3937D01*
G01X783465Y1468504D02*
X754724D01*
G01D02*
G03X750787Y1464567I0J-3937D01*
G01X779528Y1476378D02*
X754724D01*
G01X779528D02*
X754724D01*
G01X787402Y1654331D02*
Y1472441D01*
G01X779528Y1596063D02*
Y1476378D01*
G01X787402Y1654331D02*
Y1472441D01*
G01X779528Y1596063D02*
Y1476378D01*
G01X787402Y1596063D02*
G03X779528I-3937J0D01*
G01X787402D02*
G03X779528I-3937J0D01*
G01X1216535Y1658268D02*
X791339D01*
G01D02*
G03X787402Y1654331I0J-3937D01*
G01X779528D02*
G03X775591Y1658268I-3937J0D01*
G01X1216535D02*
X791339D01*
G01D02*
G03X787402Y1654331I0J-3937D01*
G01X779528D02*
G03X775591Y1658268I-3937J0D01*
G01X779528Y1654331D02*
Y1626772D01*
G01D02*
G03X787402I3937J0D01*
G01X779528Y1654331D02*
Y1626772D01*
G01D02*
G03X787402I3937J0D01*
G01X806437Y277843D02*
G03X813362Y264712I37662J11471D01*
G01X806437Y277843D02*
G03X813362Y264712I37662J11471D01*
G01X806437Y750284D02*
G03X813362Y737153I37662J11471D01*
G01X806437Y750284D02*
G03X813362Y737154I37661J11472D01*
G01X866142Y-148819D02*
Y-11811D01*
G01Y-148819D02*
G03X870079Y-152756I3937J0D01*
G01X866142Y-11811D02*
Y-148819D01*
G01D02*
G03X870079Y-152756I3937J0D01*
G01X866142Y-129134D02*
G03X858268I-3937J0D01*
G01X866142D02*
G03X858268I-3937J0D01*
G01Y-148819D02*
Y-129134D01*
G01X854331Y-152756D02*
G03X858268Y-148819I0J3937D01*
G01D02*
Y-129134D01*
G01X854331Y-152756D02*
G03X858268Y-148819I0J3937D01*
G01X1177165Y-152756D02*
X870079D01*
G01D02*
X1177165D01*
G01X858268Y-98425D02*
Y-15748D01*
G01Y-98425D02*
Y-15748D01*
G01Y-98425D02*
G03X866142I3937J0D01*
G01X858268D02*
G03X866142I3937J0D01*
G01Y-11811D02*
G03X862205Y-7874I-3937J0D01*
G01X866142Y-11811D02*
G03X862205Y-7874I-3937J0D01*
G01X927032Y-57820D02*
G03X962731I17850J-12259D01*
G01X927032Y-57821D02*
G03X962732I17850J-12258D01*
G01X927032Y-57820D02*
G03X935199Y-42571I-64908J44575D01*
G01X954565D02*
G03X935199I-9683J-3885D01*
G01X927032Y-57821D02*
G03X935199Y-42571I-64909J44573D01*
G01X954564D02*
G03X935199I-9682J-3885D01*
G01X944512Y1089122D02*
G03X978323I16905J-13531D01*
G01X944512Y1089121D02*
G03X978323I16905J-13531D01*
G01X944512Y1431641D02*
G03X978323I16905J-13531D01*
G01X944512D02*
G03X978323I16905J-13531D01*
G01X954565Y-42571D02*
G03X962731Y-57820I73077J29322D01*
G01X954564Y-42570D02*
G03X962732Y-57821I73076J29324D01*
G01X971398Y1102252D02*
G03X978323Y1089122I37661J11472D01*
G01X971398Y1102252D02*
G03X978323Y1089121I37662J11471D01*
G01X971398Y1102252D02*
G03X951437I-9980J-3039D01*
G01X971398D02*
G03X951437I-9980J-3039D01*
G01X944512Y1089122D02*
G03X951437Y1102252I-30737J24602D01*
G01X944512Y1089121D02*
G03X951437Y1102252I-30737J24602D01*
G01X971398Y1444772D02*
G03X978323Y1431641I37662J11471D01*
G01X971398Y1444772D02*
G03X978323Y1431641I37662J11471D01*
G01X971398Y1444772D02*
G03X951437I-9980J-3040D01*
G01X944512Y1431641D02*
G03X951437Y1444772I-30737J24602D01*
G01X944512Y1431641D02*
G03X951437Y1444772I-30737J24602D01*
G01X971398D02*
G03X951437I-9980J-3039D01*
G01X1181102Y-148819D02*
Y-3937D01*
G01X1177165Y-152756D02*
G03X1181102Y-148819I0J3937D01*
G01X1177165Y-152756D02*
G03X1181102Y-148819I0J3937D01*
G01D02*
Y-3937D01*
G01Y-94488D02*
G03X1188976I3937J0D01*
G01X1181102D02*
G03X1188976I3937J0D01*
G01Y-125197D02*
G03X1181102I-3937J0D01*
G01X1188976D02*
G03X1181102I-3937J0D01*
G01X1185039Y0D02*
G03X1181102Y-3937I0J-3937D01*
G01X1185039Y0D02*
G03X1181102Y-3937I0J-3937D01*
G01X1164984Y557626D02*
G03X1198795I16906J-13531D01*
G01X1164984Y557625D02*
G03X1198795I16906J-13531D01*
G01X1191870Y570756D02*
G03X1171909I-9980J-3039D01*
G01X1191870D02*
G03X1171909I-9980J-3039D01*
G01X1164984Y557626D02*
G03X1171909Y570756I-30736J24602D01*
G01X1164984Y557625D02*
G03X1171909Y570756I-30737J24602D01*
G01X1164984Y971011D02*
G03X1198795I16906J-13531D01*
G01X1164984D02*
G03X1198795I16906J-13531D01*
G01X1191870Y984142D02*
G03X1171909I-9980J-3040D01*
G01X1191870D02*
G03X1171909I-9980J-3039D01*
G01X1164984Y971011D02*
G03X1171909Y984142I-30737J24602D01*
G01X1164984Y971011D02*
G03X1171909Y984142I-30737J24602D01*
G01X1164173Y1378740D02*
Y1468504D01*
G01X1930906Y1374803D02*
X1168110D01*
G01X1164173Y1378740D02*
G03X1168110Y1374803I3937J0D01*
G01X1172047Y1382677D02*
Y1464567D01*
G01X1195669Y1382677D02*
X1172047D01*
G01X1930906Y1374803D02*
X1168110D01*
G01X1164173Y1378740D02*
G03X1168110Y1374804I3937J1D01*
G01X1164173Y1378740D02*
Y1468504D01*
G01X1172047Y1382677D02*
Y1464567D01*
G01X1195669Y1382677D02*
X1172047D01*
G01X1168110Y1472441D02*
G03X1164173Y1468504I0J-3937D01*
G01X1168110Y1472441D02*
G03X1164173Y1468504I0J-3937D01*
G01X1172047Y1464567D02*
X1216535D01*
G01X1172047D02*
X1216535D01*
G01X1168110Y1472441D02*
X1216535D01*
G01X1168110D02*
X1216535D01*
G01X1164984Y1561563D02*
G03X1171909Y1574693I-30736J24602D01*
G01X1164984Y1561562D02*
G03X1171909Y1574693I-30737J24602D01*
G01X1164984Y1561563D02*
G03X1198795I16906J-13531D01*
G01X1164984Y1561562D02*
G03X1198795I16906J-13531D01*
G01X1191870Y1574693D02*
G03X1171909I-9980J-3039D01*
G01X1191870D02*
G03X1171909I-9980J-3039D01*
G01X1188976Y-148819D02*
Y-125197D01*
G01Y-148819D02*
G03X1192913Y-152756I3937J0D01*
G01X1188976Y-148819D02*
Y-125197D01*
G01Y-148819D02*
G03X1192913Y-152756I3937J0D01*
G01D02*
X1919843D01*
G01X1192913D02*
X1919843D01*
G01X1188976Y-94488D02*
Y-7874D01*
G01Y-94488D02*
Y-7874D01*
G01X1185039Y0D02*
X1366142D01*
G01X1188976Y-7874D02*
X1315748D01*
G01X1185039Y0D02*
X1366142D01*
G01X1188976Y-7874D02*
X1315748D01*
G01X1191870Y570756D02*
G03X1198795Y557626I37662J11472D01*
G01X1191870Y570756D02*
G03X1198795Y557626I37662J11472D01*
G01X1191870Y984142D02*
G03X1198795Y971011I37662J11471D01*
G01X1191870Y984142D02*
G03X1198795Y971011I37662J11471D01*
G01X1524606Y1382677D02*
X1226378D01*
G01X1524606D02*
X1226378D01*
G01X1195669Y1374803D02*
G03Y1382677I0J3937D01*
G01X1226378D02*
G03Y1374803I0J-3937D01*
G01X1195669D02*
G03Y1382677I0J3937D01*
G01X1226378D02*
G03Y1374803I0J-3937D01*
G01X1216535Y1464567D02*
G03X1228346Y1476378I0J11811D01*
G01X1216535Y1464567D02*
G03X1228346Y1476378I0J11811D01*
G01Y1592126D02*
Y1476378D01*
G01Y1592126D02*
Y1476378D01*
G01X1220472Y1654331D02*
Y1476378D01*
G01X1216535Y1472441D02*
G03X1220472Y1476378I0J3937D01*
G01X1216535Y1472441D02*
G03X1220472Y1476378I0J3937D01*
G01D02*
Y1654331D01*
G01X1191870Y1574693D02*
G03X1198795Y1561563I37662J11472D01*
G01X1191870Y1574693D02*
G03X1198795Y1561562I37662J11471D01*
G01X1228346Y1592126D02*
G03X1220472I-3937J0D01*
G01X1228346D02*
G03X1220472I-3937J0D01*
G01X1232283Y1658268D02*
X1442382D01*
G01X1232283D02*
G03X1228346Y1654331I0J-3937D01*
G01X1232283Y1658268D02*
X1442382D01*
G01X1232283D02*
G03X1228346Y1654331I0J-3937D01*
G01D02*
Y1622835D01*
G01Y1654331D02*
Y1622835D01*
G01X1220472Y1654331D02*
G03X1216535Y1658268I-3937J0D01*
G01X1220472Y1654331D02*
G03X1216535Y1658268I-3937J0D01*
G01X1220472Y1622835D02*
G03X1228346I3937J0D01*
G01X1220472D02*
G03X1228346I3937J0D01*
G01X1284965Y378885D02*
G03X1318776I16906J-13531D01*
G01X1284965D02*
G03X1318775I16905J-13531D01*
G01X1284965Y831641D02*
G03X1318776I16906J-13531D01*
G01X1284965D02*
G03X1318775I16905J-13531D01*
G01X1284965Y1284397D02*
G03X1318776I16906J-13531D01*
G01X1284965D02*
G03X1318775I16905J-13531D01*
G01X1315748Y-7874D02*
G03Y0I0J3937D01*
G01Y-7874D02*
G03Y0I0J3937D01*
G01X1311850Y392016D02*
G03X1291890I-9980J-3040D01*
G01X1311850D02*
G03X1318776Y378885I37662J11473D01*
G01X1311851Y392016D02*
G03X1291890I-9980J-3039D01*
G01X1311851D02*
G03X1318775Y378885I37663J11469D01*
G01X1284965D02*
G03X1291890Y392016I-30737J24602D01*
G01X1284965Y378885D02*
G03X1291890Y392016I-30737J24602D01*
G01X1284965Y831641D02*
G03X1291890Y844772I-30737J24602D01*
G01X1311850D02*
G03X1318776Y831641I37662J11473D01*
G01X1284965D02*
G03X1291890Y844772I-30737J24602D01*
G01X1311851D02*
G03X1318775Y831641I37663J11469D01*
G01X1311850Y844772D02*
G03X1291890I-9980J-3040D01*
G01X1311851D02*
G03X1291890I-9980J-3039D01*
G01X1284965Y1284397D02*
G03X1291890Y1297528I-30737J24602D01*
G01X1311850D02*
G03X1291890I-9980J-3040D01*
G01X1311850D02*
G03X1318776Y1284397I37661J11473D01*
G01X1284965D02*
G03X1291890Y1297528I-30737J24602D01*
G01X1311851D02*
G03X1291890I-9980J-3040D01*
G01X1311851D02*
G03X1318775Y1284397I37663J11469D01*
G01X1377953Y3937D02*
Y51181D01*
G01Y3937D02*
Y51181D01*
G01X1370079Y3937D02*
Y55118D01*
G01X1366142Y0D02*
G03X1370079Y3937I0J3937D01*
G01X1366142Y-7874D02*
G03X1377953Y3937I0J11811D01*
G01X1346457Y-7874D02*
X1366142D01*
G01Y0D02*
G03X1370079Y3937I0J3937D01*
G01D02*
Y55118D01*
G01X1346457Y-7874D02*
X1366142D01*
G01D02*
G03X1377953Y3937I0J11811D01*
G01X1346457Y0D02*
G03Y-7874I0J-3937D01*
G01Y0D02*
G03Y-7874I0J-3937D01*
G01X1374016Y59055D02*
G03X1370079Y55118I0J-3937D01*
G01X1374016Y59056D02*
G03X1370079Y55118I0J-3937D01*
G01X1374016Y59055D02*
X1555118D01*
G01X1377953Y51181D02*
X1551181D01*
G01X1374016Y59055D02*
X1555118D01*
G01X1377953Y51181D02*
X1551181D01*
G01X1442382Y1658268D02*
G03X1450256I3937J0D01*
G01X1442382D02*
G03X1450256I3937J0D01*
G01D02*
X1919843D01*
G01X1450256D02*
X1919843D01*
G01X1562992Y0D02*
X1930906D01*
G01X1559055Y55118D02*
Y3937D01*
G01D02*
G03X1562992Y0I3937J0D01*
G01Y-7874D02*
X1593701D01*
G01X1559055Y55118D02*
Y3937D01*
G01D02*
G03X1562992Y0I3937J0D01*
G01D02*
X1930906D01*
G01X1562992Y-7874D02*
X1593701D01*
G01X1551181Y51181D02*
Y3937D01*
G01D02*
G03X1562992Y-7874I11811J0D01*
G01X1551181Y51181D02*
Y3937D01*
G01D02*
G03X1562992Y-7874I11811J0D01*
G01X1559055Y55118D02*
G03X1555118Y59055I-3937J0D01*
G01X1559055Y55118D02*
G03X1555118Y59055I-3937J0D01*
G01X1532996Y378885D02*
G03X1566807I16906J-13531D01*
G01X1532996D02*
G03X1566807I16906J-13531D01*
G01X1559882Y392016D02*
G03X1566807Y378885I37662J11471D01*
G01X1559882Y392016D02*
G03X1566807Y378885I37662J11471D01*
G01X1559882Y392016D02*
G03X1539921I-9980J-3039D01*
G01X1559882D02*
G03X1539921I-9980J-3039D01*
G01X1532996Y378885D02*
G03X1539921Y392016I-30737J24602D01*
G01X1532996Y378885D02*
G03X1539921Y392016I-30737J24602D01*
G01X1559882Y844772D02*
G03X1566807Y831641I37662J11471D01*
G01X1559882Y844772D02*
G03X1566807Y831641I37662J11471D01*
G01X1532996D02*
G03X1539921Y844772I-30737J24602D01*
G01X1532996Y831641D02*
G03X1539921Y844772I-30737J24602D01*
G01X1532996Y831641D02*
G03X1566807I16906J-13531D01*
G01X1532996D02*
G03X1566807I16906J-13531D01*
G01X1559882Y844772D02*
G03X1539921I-9980J-3040D01*
G01X1559882D02*
G03X1539921I-9980J-3039D01*
G01X1532996Y1284397D02*
G03X1566807I16906J-13531D01*
G01X1532996D02*
G03X1566807I16906J-13531D01*
G01X1559882Y1297528D02*
G03X1566807Y1284397I37662J11471D01*
G01X1559882Y1297528D02*
G03X1566807Y1284397I37662J11471D01*
G01X1559882Y1297528D02*
G03X1539921I-9980J-3040D01*
G01X1532996Y1284397D02*
G03X1539921Y1297528I-30737J24602D01*
G01X1532996Y1284397D02*
G03X1539921Y1297528I-30737J24602D01*
G01X1559882D02*
G03X1539921I-9980J-3040D01*
G01X1563976Y1382677D02*
G03Y1374803I0J-3937D01*
G01Y1382677D02*
G03Y1374803I0J-3937D01*
G01X1524606D02*
G03Y1382677I0J3937D01*
G01Y1374803D02*
G03Y1382677I0J3937D01*
G01X1864567D02*
X1563976D01*
G01X1864567D02*
X1563976D01*
G01X1593701Y-7874D02*
G03Y0I0J3937D01*
G01Y-7874D02*
G03Y0I0J3937D01*
G01X1633071D02*
G03Y-7874I0J-3937D01*
G01D02*
X1880512D01*
G01X1633071D02*
X1880512D01*
G01X1633071Y0D02*
G03Y-7874I0J-3937D01*
G01X1693996Y829921D02*
G03X1653839I-20078J0D01*
G01X1693996D02*
G03I-20079J0D01*
G01X1653839D02*
G03X1693996I20078J0D01*
G01X1781028Y378885D02*
G03X1814839I16906J-13531D01*
G01X1781028D02*
G03X1814838I16905J-13531D01*
G01X1807913Y392016D02*
G03X1814839Y378885I37662J11473D01*
G01X1807914Y392016D02*
G03X1814838Y378885I37663J11469D01*
G01X1807913Y392016D02*
G03X1787953I-9980J-3040D01*
G01X1807914D02*
G03X1787953I-9980J-3039D01*
G01X1781028Y378885D02*
G03X1787953Y392016I-30737J24602D01*
G01X1781028Y378885D02*
G03X1787953Y392016I-30737J24602D01*
G01X1807913Y844772D02*
G03X1814839Y831641I37662J11473D01*
G01X1807914Y844772D02*
G03X1814838Y831641I37663J11469D01*
G01X1781028D02*
G03X1787953Y844772I-30737J24602D01*
G01X1781028Y831641D02*
G03X1787953Y844772I-30737J24602D01*
G01X1781028Y831641D02*
G03X1814839I16906J-13531D01*
G01X1781028D02*
G03X1814838I16905J-13531D01*
G01X1807913Y844772D02*
G03X1787953I-9980J-3040D01*
G01X1807914D02*
G03X1787953I-9980J-3039D01*
G01X1781028Y1284397D02*
G03X1814839I16906J-13531D01*
G01X1781028D02*
G03X1814838I16905J-13531D01*
G01X1807913Y1297528D02*
G03X1814839Y1284397I37661J11473D01*
G01X1807914Y1297528D02*
G03X1814838Y1284397I37663J11469D01*
G01X1807913Y1297528D02*
G03X1787953I-9980J-3040D01*
G01X1781028Y1284397D02*
G03X1787953Y1297528I-30737J24602D01*
G01X1781028Y1284397D02*
G03X1787953Y1297528I-30737J24602D01*
G01X1807914D02*
G03X1787953I-9980J-3040D01*
G01X1911220Y0D02*
G03Y-7874I0J-3937D01*
G01Y0D02*
G03Y-7874I0J-3937D01*
G01X1880512D02*
G03Y0I0J3937D01*
G01Y-7874D02*
G03Y0I0J3937D01*
G01X1930906Y1382677D02*
X1895276D01*
G01D02*
G03Y1374803I0J-3937D01*
G01X1930906Y1382677D02*
X1895276D01*
G01D02*
G03Y1374803I0J-3937D01*
G01X1864567D02*
G03Y1382677I0J3937D01*
G01Y1374803D02*
G03Y1382677I0J3937D01*
G01X1919843Y-152756D02*
G03X1934843Y-137756I0J15000D01*
G01X1919843Y-152756D02*
G03X1934843Y-137756I0J15000D01*
G01Y-11811D02*
Y-137756D01*
G01Y-11811D02*
Y-137756D01*
G01X1930906Y0D02*
G03X1934843Y3937I0J3937D01*
G01X1930906Y0D02*
G03X1934843Y3937I0J3937D01*
G01Y-11811D02*
G03X1930906Y-7874I-3937J0D01*
G01X1934843Y-11811D02*
G03X1930906Y-7874I-3937J0D01*
G01X1911220D02*
X1930906D01*
G01X1911220D02*
X1930906D01*
G01X1934843Y1370866D02*
Y3937D01*
G01D02*
Y1370866D01*
G01D02*
G03X1930906Y1374803I-3937J0D01*
G01X1934843Y1370866D02*
G03X1930906Y1374803I-3937J0D01*
G01Y1382677D02*
G03X1934843Y1386614I0J3937D01*
G01X1930906Y1382677D02*
G03X1934843Y1386614I0J3937D01*
G01D02*
Y1643268D01*
G01Y1386614D02*
Y1643268D01*
G01D02*
G03X1919843Y1658268I-15000J0D01*
G01X1934843Y1643268D02*
G03X1919843Y1658268I-15000J0D01*
G54D19*
X72837Y181361D03*
Y634117D03*
Y1086873D03*
X140372Y739924D03*
X133063Y1009425D03*
X197049Y181361D03*
X199763Y597425D03*
X197449Y1086873D03*
X264739Y739668D03*
X337721Y125355D03*
X321362Y181361D03*
X321262Y634117D03*
Y1086873D03*
X365162Y95870D03*
X388796Y739596D03*
X389067Y1169730D03*
X445474Y181361D03*
Y634117D03*
X457173Y1075426D03*
X445573Y1107526D03*
X525579Y544981D03*
X512892Y739849D03*
X569687Y181361D03*
X575779Y520031D03*
X557279D03*
X594267Y534070D03*
X569687Y634117D03*
Y1086873D03*
X611910Y555074D03*
X637326Y739766D03*
X666142Y109919D03*
X693900Y181361D03*
Y1086873D03*
X752500Y1151700D03*
X877673Y865103D03*
X882400Y865068D03*
X876748Y1358507D03*
X876740Y1350414D03*
X882445Y1410997D03*
X877445D03*
X886792Y1411114D03*
X868500Y1439200D03*
X886500D03*
X877500D03*
X888600Y1485950D03*
X923600Y912400D03*
X928100D03*
X919100D03*
X932361Y962907D03*
X920607Y962782D03*
X936861Y962907D03*
X926100Y981900D03*
X930600D03*
X917100D03*
X929105Y1031960D03*
X920879Y1032103D03*
X932559Y1366984D03*
X932564Y1353312D03*
X936994Y1376548D03*
X926500Y1506400D03*
X942000D03*
X896335Y1528408D03*
X896365Y1519992D03*
X961500Y911700D03*
X966000D03*
X963900Y957100D03*
X950500Y982700D03*
X959500D03*
X946000D03*
X960400Y1027500D03*
X951872Y1365302D03*
X947125Y1376357D03*
X946300Y1506400D03*
X972413Y1549366D03*
X963488Y1520439D03*
X1039100Y908400D03*
X1020480Y908200D03*
X1015728D03*
X1023100Y959450D03*
X997694Y981540D03*
X1011194D03*
X993194D03*
X1017194Y1030640D03*
X1032500Y1073700D03*
X1037000D03*
X1023500D03*
X1035900Y1121500D03*
X1013400Y1144200D03*
X1004300D03*
X999700D03*
X1043112Y-38608D03*
X1066225Y-44000D03*
X1074400Y-73668D03*
X1046803Y876127D03*
X1042101Y880641D03*
X1043900Y908400D03*
X1053200D03*
X1073500Y1073700D03*
X1069000D03*
X1082500D03*
X1110500Y1073800D03*
X1119700D03*
X1124500D03*
X1128800Y1121900D03*
X1092200Y1122600D03*
X1176300Y296100D03*
X1180953Y296185D03*
X1176100Y277600D03*
X1176500Y1120200D03*
X1215547Y256715D03*
X1185588Y296150D03*
X1190200Y296100D03*
X1199000Y295700D03*
X1323521Y86155D03*
X1318821D03*
X1304563Y90958D03*
X1307500Y169361D03*
Y622117D03*
X1305100Y1074873D03*
X1354437Y84938D03*
X1337634Y133788D03*
X1421969Y520457D03*
X1413400Y571300D03*
X1431713Y169361D03*
X1470700Y528800D03*
X1435200Y521800D03*
X1448261Y521734D03*
X1456439Y521766D03*
X1447700Y575800D03*
X1474700D03*
X1431713Y622117D03*
Y1074873D03*
X1478700Y575800D03*
X1555925Y169361D03*
Y622117D03*
Y1074873D03*
X1585757Y129704D03*
X1602200Y1114600D03*
X1680138Y169361D03*
Y622117D03*
Y1074873D03*
X1804350Y169361D03*
Y622117D03*
X1774863Y1021425D03*
X1800750Y1074673D03*
X1855517Y165175D03*
X1843917Y197375D03*
X1855417Y617931D03*
X1843917Y650131D03*
X1840433Y1103341D03*
X1836431Y1147859D03*
X1868100Y1062200D03*
G54D55*
X543338Y553169D03*
X567779Y570531D03*
X575779D03*
X588779D03*
X562279D03*
X876956Y1365750D03*
X929232Y921850D03*
X928194Y1373048D03*
X942879Y1361757D03*
X931500Y1556900D03*
X937000D03*
X973055Y1179453D03*
X945000Y1556900D03*
X958000D03*
X1032053Y-42075D03*
X999500Y1184200D03*
X1054625Y-47250D03*
X1320055Y71629D03*
X1436200Y549800D03*
X1459200Y572300D03*
X1598400Y1111200D03*
G54D28*
X61737Y254661D03*
X54137D03*
X61737Y707417D03*
X54137D03*
X61737Y1160173D03*
X54137D03*
X117994Y966075D03*
X103200Y975500D03*
X110800D03*
X103200Y967900D03*
X110800D03*
X169900Y563500D03*
Y555900D03*
X125594Y966075D03*
X185949Y254661D03*
X178349D03*
X184694Y554075D03*
X192294D03*
X177500Y563500D03*
Y555900D03*
X185949Y707417D03*
X178349D03*
X185949Y1160173D03*
X178349D03*
X310162Y254661D03*
X302562D03*
X310162Y707417D03*
X302562D03*
X310162Y1160173D03*
X302562D03*
X434374Y254661D03*
X426774D03*
X434374Y707417D03*
X426774D03*
X449338Y1160696D03*
X441738D03*
X550987Y254661D03*
Y707417D03*
Y1160173D03*
X558587Y254661D03*
X581036Y506682D03*
X588636D03*
X558587Y707417D03*
Y1160173D03*
X648465Y577467D03*
X682800Y254661D03*
X675200D03*
X656065Y577467D03*
X682800Y707417D03*
X675200D03*
X682800Y1160173D03*
X675200D03*
X826362Y43947D03*
X833962D03*
X861930Y43376D03*
X869530D03*
X861536Y75972D03*
X869136D03*
X1180068Y716700D03*
X1197068Y58168D03*
X1189468D03*
X1187668Y716700D03*
X1448662Y588301D03*
X1441062D03*
X1759794Y978075D03*
X1745000Y987500D03*
X1752600D03*
X1745000Y979900D03*
X1752600D03*
X1767394Y978075D03*
X1853469Y254661D03*
X1845869D03*
X1849876Y707417D03*
X1842276D03*
G54D37*
X99823Y211142D03*
Y207992D03*
Y204842D03*
Y201693D03*
Y198543D03*
Y217441D03*
Y214291D03*
Y670197D03*
Y667047D03*
Y663898D03*
Y660748D03*
Y657598D03*
Y654449D03*
Y651299D03*
Y1122953D03*
Y1119803D03*
Y1116654D03*
Y1113504D03*
Y1110354D03*
Y1107205D03*
Y1104055D03*
X224035Y211142D03*
Y207992D03*
Y204842D03*
Y201693D03*
Y198543D03*
Y217441D03*
Y214291D03*
Y670197D03*
Y667047D03*
Y663898D03*
Y660748D03*
Y657598D03*
Y654449D03*
Y651299D03*
Y1122953D03*
Y1119803D03*
Y1116654D03*
Y1113504D03*
Y1110354D03*
Y1107205D03*
Y1104055D03*
X348248Y211142D03*
Y207992D03*
Y204842D03*
Y201693D03*
Y198543D03*
Y217441D03*
Y214291D03*
Y670197D03*
Y667047D03*
Y663898D03*
Y660748D03*
Y657598D03*
Y654449D03*
Y651299D03*
Y1122953D03*
Y1119803D03*
Y1116654D03*
Y1113504D03*
Y1110354D03*
Y1107205D03*
Y1104055D03*
X472460Y211142D03*
Y207992D03*
Y204842D03*
Y201693D03*
Y198543D03*
Y217441D03*
Y214291D03*
Y670197D03*
Y667047D03*
Y663898D03*
Y660748D03*
Y657598D03*
Y654449D03*
Y651299D03*
Y1122953D03*
Y1119803D03*
Y1116654D03*
Y1113504D03*
Y1110354D03*
Y1107205D03*
Y1104055D03*
X596673Y211142D03*
Y207992D03*
Y204842D03*
Y201693D03*
Y198543D03*
Y217441D03*
Y214291D03*
Y670197D03*
Y667047D03*
Y663898D03*
Y660748D03*
Y657598D03*
Y654449D03*
Y651299D03*
Y1122953D03*
Y1119803D03*
Y1116654D03*
Y1113504D03*
Y1110354D03*
Y1107205D03*
Y1104055D03*
X720886Y211142D03*
Y207992D03*
Y204842D03*
Y201693D03*
Y198543D03*
Y217441D03*
Y214291D03*
Y670197D03*
Y667047D03*
Y663898D03*
Y660748D03*
Y657598D03*
Y654449D03*
Y651299D03*
Y1122953D03*
Y1119803D03*
Y1116654D03*
Y1113504D03*
Y1110354D03*
Y1107205D03*
Y1104055D03*
X1270492Y211142D03*
Y207992D03*
Y204842D03*
Y201693D03*
Y198543D03*
Y217441D03*
Y214291D03*
Y670197D03*
Y667047D03*
Y663898D03*
Y660748D03*
Y657598D03*
Y654449D03*
Y651299D03*
Y1122953D03*
Y1119803D03*
Y1116654D03*
Y1113504D03*
Y1110354D03*
Y1107205D03*
Y1104055D03*
X1394705Y211142D03*
Y207992D03*
Y204842D03*
Y201693D03*
Y198543D03*
Y217441D03*
Y214291D03*
Y670197D03*
Y667047D03*
Y663898D03*
Y660748D03*
Y657598D03*
Y654449D03*
Y651299D03*
Y1122953D03*
Y1119803D03*
Y1116654D03*
Y1113504D03*
Y1110354D03*
Y1107205D03*
Y1104055D03*
X1518917Y211142D03*
Y207992D03*
Y204842D03*
Y201693D03*
Y198543D03*
Y217441D03*
Y214291D03*
Y670197D03*
Y667047D03*
Y663898D03*
Y660748D03*
Y657598D03*
Y654449D03*
Y651299D03*
Y1122953D03*
Y1119803D03*
Y1116654D03*
Y1113504D03*
Y1110354D03*
Y1107205D03*
Y1104055D03*
X1643130Y211142D03*
Y207992D03*
Y204842D03*
Y201693D03*
Y198543D03*
Y217441D03*
Y214291D03*
Y670197D03*
Y667047D03*
Y663898D03*
Y660748D03*
Y657598D03*
Y654449D03*
Y651299D03*
Y1122953D03*
Y1119803D03*
Y1116654D03*
Y1113504D03*
Y1110354D03*
Y1107205D03*
Y1104055D03*
X1767342Y211142D03*
Y207992D03*
Y204842D03*
Y201693D03*
Y198543D03*
Y217441D03*
Y214291D03*
Y670197D03*
Y667047D03*
Y663898D03*
Y660748D03*
Y657598D03*
Y654449D03*
Y651299D03*
Y1122953D03*
Y1119803D03*
Y1116654D03*
Y1113504D03*
Y1110354D03*
Y1107205D03*
Y1104055D03*
X1891555Y211142D03*
Y207992D03*
Y204842D03*
Y201693D03*
Y198543D03*
Y217441D03*
Y214291D03*
Y670197D03*
Y667047D03*
Y663898D03*
Y660748D03*
Y657598D03*
Y654449D03*
Y651299D03*
Y1122953D03*
Y1119803D03*
Y1116654D03*
Y1113504D03*
Y1110354D03*
Y1107205D03*
Y1104055D03*
G54D64*
X683341Y586324D03*
X689747D03*
G54D73*
X895676Y1372183D03*
Y1369623D03*
Y1367063D03*
Y1364503D03*
Y1361943D03*
Y1359383D03*
Y1356823D03*
Y1374743D03*
X917876Y1356823D03*
Y1359383D03*
Y1361943D03*
Y1364503D03*
Y1367063D03*
Y1369623D03*
Y1372183D03*
Y1374743D03*
G54D46*
X145237Y256161D03*
Y708917D03*
Y1161673D03*
X269449Y256161D03*
Y708917D03*
Y1161673D03*
X393662Y256161D03*
Y708917D03*
X393462Y1161673D03*
X505674Y1130873D03*
X517874Y256161D03*
Y708917D03*
X531474Y1152773D03*
X642087Y256161D03*
Y708917D03*
Y1161673D03*
X833108Y37372D03*
X868377Y37234D03*
X937809Y991763D03*
X914882Y1534500D03*
X1113100Y-48400D03*
X1435000Y544600D03*
X1460061Y588256D03*
X1503682Y539100D03*
X1887132Y1054227D03*
G54D82*
X1065716Y1546420D03*
X1094000D03*
G54D56*
X543338Y556769D03*
X567779Y574131D03*
X575779D03*
X588779D03*
X562279D03*
X876956Y1369350D03*
X929232Y925450D03*
X942879Y1365357D03*
X928194Y1376648D03*
X931500Y1560500D03*
X937000D03*
X973055Y1183053D03*
X945000Y1560500D03*
X958000D03*
X1032053Y-38475D03*
X999500Y1187800D03*
X1054625Y-43650D03*
X1320055Y75229D03*
X1436200Y553400D03*
X1459200Y575900D03*
X1598400Y1114800D03*
G54D29*
X50937Y245661D03*
X55937D03*
X60937D03*
X65937D03*
Y225661D03*
X60937D03*
X55937D03*
X50937D03*
Y698417D03*
X55937D03*
X60937D03*
X65937D03*
Y678417D03*
X60937D03*
X55937D03*
X50937D03*
X65937Y1131173D03*
X60937D03*
X55937D03*
X50937D03*
Y1151173D03*
X55937D03*
X60937D03*
X65937D03*
X88937Y207661D03*
X83937D03*
X78937D03*
X73937D03*
Y227661D03*
X78937D03*
X83937D03*
X88937D03*
Y660417D03*
X83937D03*
X78937D03*
X73937D03*
Y680417D03*
X78937D03*
X83937D03*
X88937D03*
Y1113173D03*
X83937D03*
X78937D03*
X73937D03*
Y1133173D03*
X78937D03*
X83937D03*
X88937D03*
X213149Y207661D03*
X208149D03*
X203149D03*
X198149D03*
X175149Y245661D03*
X180149D03*
X185149D03*
X190149D03*
Y225661D03*
X185149D03*
X180149D03*
X175149D03*
X198149Y227661D03*
X203149D03*
X208149D03*
X213149D03*
X175149Y698417D03*
X180149D03*
X185149D03*
X190149D03*
Y678417D03*
X185149D03*
X180149D03*
X175149D03*
X213149Y660417D03*
X208149D03*
X203149D03*
X198149D03*
Y680417D03*
X203149D03*
X208149D03*
X213149D03*
X190149Y1131173D03*
X185149D03*
X180149D03*
X175149D03*
X213149Y1113173D03*
X208149D03*
X203149D03*
X198149D03*
Y1133173D03*
X203149D03*
X208149D03*
X213149D03*
X175149Y1151173D03*
X180149D03*
X185149D03*
X190149D03*
X299362Y245661D03*
X304362D03*
X309362D03*
X314362D03*
Y225661D03*
X309362D03*
X304362D03*
X299362D03*
Y698417D03*
X304362D03*
X309362D03*
X314362D03*
Y678417D03*
X309362D03*
X304362D03*
X299362D03*
X314362Y1131173D03*
X309362D03*
X304362D03*
X299362D03*
Y1151173D03*
X304362D03*
X309362D03*
X314362D03*
X337362Y207661D03*
X332362D03*
X327362D03*
X322362D03*
Y227661D03*
X327362D03*
X332362D03*
X337362D03*
Y660417D03*
X332362D03*
X327362D03*
X322362D03*
Y680417D03*
X327362D03*
X332362D03*
X337362D03*
Y1113173D03*
X332362D03*
X327362D03*
X322362D03*
Y1133173D03*
X327362D03*
X332362D03*
X337362D03*
X456574Y207661D03*
X451574D03*
X446574D03*
Y227661D03*
X451574D03*
X456574D03*
X423574Y245661D03*
X428574D03*
X433574D03*
X438574D03*
Y225661D03*
X433574D03*
X428574D03*
X423574D03*
Y698417D03*
X428574D03*
X433574D03*
X438574D03*
Y678417D03*
X433574D03*
X428574D03*
X423574D03*
X456574Y660417D03*
X451574D03*
X446574D03*
Y680417D03*
X451574D03*
X456574D03*
X457100Y1130200D03*
X452100D03*
X447100D03*
Y1150200D03*
X452100D03*
X457100D03*
X461574Y207661D03*
Y227661D03*
Y660417D03*
Y680417D03*
X462100Y1130200D03*
Y1150200D03*
X547787Y245661D03*
X552787D03*
Y225661D03*
X547787D03*
Y698417D03*
X552787D03*
Y678417D03*
X547787D03*
X552787Y1131173D03*
X547787D03*
X529474Y1113073D03*
X524474D03*
X519474D03*
X514474D03*
Y1133073D03*
X519474D03*
X524474D03*
X529474D03*
X547787Y1151173D03*
X552787D03*
X585787Y207661D03*
X580787D03*
X575787D03*
X570787D03*
Y227661D03*
X575787D03*
X580787D03*
X585787D03*
X557787Y245661D03*
X562787D03*
Y225661D03*
X557787D03*
Y698417D03*
X562787D03*
Y678417D03*
X557787D03*
X585787Y660417D03*
X580787D03*
X575787D03*
X570787D03*
Y680417D03*
X575787D03*
X580787D03*
X585787D03*
X562787Y1131173D03*
X557787D03*
X585787Y1113173D03*
X580787D03*
X575787D03*
X570787D03*
Y1133173D03*
X575787D03*
X580787D03*
X585787D03*
X557787Y1151173D03*
X562787D03*
X700000Y207661D03*
X695000D03*
Y227661D03*
X700000D03*
X672000Y245661D03*
X677000D03*
X682000D03*
X687000D03*
Y225661D03*
X682000D03*
X677000D03*
X672000D03*
Y698417D03*
X677000D03*
X682000D03*
X687000D03*
Y678417D03*
X682000D03*
X677000D03*
X672000D03*
X700000Y660417D03*
X695000D03*
Y680417D03*
X700000D03*
X687000Y1131173D03*
X682000D03*
X677000D03*
X672000D03*
X700000Y1113173D03*
X695000D03*
Y1133173D03*
X700000D03*
X672000Y1151173D03*
X677000D03*
X682000D03*
X687000D03*
X710000Y207661D03*
X705000D03*
Y227661D03*
X710000D03*
Y660417D03*
X705000D03*
Y680417D03*
X710000D03*
Y1113173D03*
X705000D03*
Y1133173D03*
X710000D03*
X999500Y1174500D03*
X1004500D03*
X1009500D03*
X1014500D03*
Y1154500D03*
X1009500D03*
X1004500D03*
X999500D03*
X1318500Y254161D03*
X1323500D03*
X1328500D03*
Y234161D03*
X1323500D03*
X1318500D03*
X1328500Y686917D03*
X1323500D03*
X1318500D03*
Y706917D03*
X1323500D03*
X1328500D03*
X1318500Y1159673D03*
X1323500D03*
X1328500D03*
Y1139673D03*
X1323500D03*
X1318500D03*
X1333500Y254161D03*
Y234161D03*
Y686917D03*
Y706917D03*
Y1159673D03*
Y1139673D03*
X1442713Y254161D03*
X1447713D03*
X1452713D03*
X1457713D03*
Y234161D03*
X1452713D03*
X1447713D03*
X1442713D03*
X1457713Y686917D03*
X1452713D03*
X1447713D03*
X1442713D03*
Y706917D03*
X1447713D03*
X1452713D03*
X1457713D03*
X1442713Y1159673D03*
X1447713D03*
X1452713D03*
X1457713D03*
Y1139673D03*
X1452713D03*
X1447713D03*
X1442713D03*
X1566925Y254161D03*
X1571925D03*
Y234161D03*
X1566925D03*
X1571925Y686917D03*
X1566925D03*
Y706917D03*
X1571925D03*
X1564073Y1105175D03*
X1559073D03*
X1554073D03*
X1549073D03*
Y1125175D03*
X1554073D03*
X1559073D03*
X1564073D03*
X1576925Y254161D03*
X1581925D03*
Y234161D03*
X1576925D03*
X1581925Y686917D03*
X1576925D03*
Y706917D03*
X1581925D03*
X1691138Y254161D03*
X1696138D03*
X1701138D03*
X1706138D03*
Y234161D03*
X1701138D03*
X1696138D03*
X1691138D03*
X1706138Y686917D03*
X1701138D03*
X1696138D03*
X1691138D03*
Y706917D03*
X1696138D03*
X1701138D03*
X1706138D03*
X1691138Y1159673D03*
X1696138D03*
X1701138D03*
X1706138D03*
Y1139673D03*
X1701138D03*
X1696138D03*
X1691138D03*
X1842669Y245661D03*
X1847669D03*
X1852669D03*
X1857669D03*
Y225661D03*
X1852669D03*
X1847669D03*
X1842669D03*
X1815350Y254161D03*
X1820350D03*
X1825350D03*
X1830350D03*
Y234161D03*
X1825350D03*
X1820350D03*
X1815350D03*
X1842669Y698417D03*
X1847669D03*
X1852669D03*
X1857669D03*
Y678417D03*
X1852669D03*
X1847669D03*
X1842669D03*
X1830350Y686917D03*
X1825350D03*
X1820350D03*
X1815350D03*
Y706917D03*
X1820350D03*
X1825350D03*
X1830350D03*
X1858277Y1125264D03*
X1853277D03*
X1848277D03*
X1843277D03*
Y1145264D03*
X1848277D03*
X1853277D03*
X1858277D03*
X1815350Y1159673D03*
X1820350D03*
X1825350D03*
X1830350D03*
Y1139673D03*
X1825350D03*
X1820350D03*
X1815350D03*
X1880669Y207661D03*
X1875669D03*
X1870669D03*
X1865669D03*
Y227661D03*
X1870669D03*
X1875669D03*
X1880669D03*
Y660417D03*
X1875669D03*
X1870669D03*
X1865669D03*
Y680417D03*
X1870669D03*
X1875669D03*
X1880669D03*
X1880779Y1097763D03*
X1875779D03*
X1870779D03*
X1865779D03*
Y1117763D03*
X1870779D03*
X1875779D03*
X1880779D03*
G54D74*
X991713Y-122342D03*
X986713D03*
X981713D03*
X976713D03*
X971713D03*
X966713D03*
X961713D03*
X1036713D03*
X1031713D03*
X1026713D03*
X1021713D03*
X1016713D03*
X1086713D03*
X1081713D03*
X1076713D03*
X1071713D03*
X1066713D03*
X1061713D03*
X1056713D03*
X1051713D03*
X1046713D03*
X1041713D03*
G54D38*
X118209Y195492D03*
Y190492D03*
Y185492D03*
Y180492D03*
Y175492D03*
Y170492D03*
Y165492D03*
Y260492D03*
Y255492D03*
Y250492D03*
Y245492D03*
Y240492D03*
Y235492D03*
Y230492D03*
Y225492D03*
Y220492D03*
Y290492D03*
Y285492D03*
Y280492D03*
Y275492D03*
Y270492D03*
Y265492D03*
Y648248D03*
Y643248D03*
Y638248D03*
Y633248D03*
Y628248D03*
Y623248D03*
Y618248D03*
Y693248D03*
Y688248D03*
Y683248D03*
Y678248D03*
Y673248D03*
Y743248D03*
Y738248D03*
Y733248D03*
Y728248D03*
Y723248D03*
Y718248D03*
Y713248D03*
Y708248D03*
Y703248D03*
Y698248D03*
Y1081004D03*
Y1076004D03*
Y1071004D03*
Y1131004D03*
Y1126004D03*
Y1101004D03*
Y1096004D03*
Y1091004D03*
Y1086004D03*
Y1176004D03*
Y1171004D03*
Y1166004D03*
Y1161004D03*
Y1156004D03*
Y1151004D03*
Y1146004D03*
Y1141004D03*
Y1136004D03*
Y1196004D03*
Y1191004D03*
Y1186004D03*
Y1181004D03*
X242421Y195492D03*
Y190492D03*
Y185492D03*
Y180492D03*
Y175492D03*
Y170492D03*
Y165492D03*
Y260492D03*
Y255492D03*
Y250492D03*
Y245492D03*
Y240492D03*
Y235492D03*
Y230492D03*
Y225492D03*
Y220492D03*
Y290492D03*
Y285492D03*
Y280492D03*
Y275492D03*
Y270492D03*
Y265492D03*
Y648248D03*
Y643248D03*
Y638248D03*
Y633248D03*
Y628248D03*
Y623248D03*
Y618248D03*
Y693248D03*
Y688248D03*
Y683248D03*
Y678248D03*
Y673248D03*
Y743248D03*
Y738248D03*
Y733248D03*
Y728248D03*
Y723248D03*
Y718248D03*
Y713248D03*
Y708248D03*
Y703248D03*
Y698248D03*
Y1081004D03*
Y1076004D03*
Y1071004D03*
Y1131004D03*
Y1126004D03*
Y1101004D03*
Y1096004D03*
Y1091004D03*
Y1086004D03*
Y1176004D03*
Y1171004D03*
Y1166004D03*
Y1161004D03*
Y1156004D03*
Y1151004D03*
Y1146004D03*
Y1141004D03*
Y1136004D03*
Y1196004D03*
Y1191004D03*
Y1186004D03*
Y1181004D03*
X366634Y195492D03*
Y190492D03*
Y185492D03*
Y180492D03*
Y175492D03*
Y170492D03*
Y165492D03*
Y260492D03*
Y255492D03*
Y250492D03*
Y245492D03*
Y240492D03*
Y235492D03*
Y230492D03*
Y225492D03*
Y220492D03*
Y290492D03*
Y285492D03*
Y280492D03*
Y275492D03*
Y270492D03*
Y265492D03*
Y648248D03*
Y643248D03*
Y638248D03*
Y633248D03*
Y628248D03*
Y623248D03*
Y618248D03*
Y693248D03*
Y688248D03*
Y683248D03*
Y678248D03*
Y673248D03*
Y743248D03*
Y738248D03*
Y733248D03*
Y728248D03*
Y723248D03*
Y718248D03*
Y713248D03*
Y708248D03*
Y703248D03*
Y698248D03*
Y1081004D03*
Y1076004D03*
Y1071004D03*
Y1131004D03*
Y1126004D03*
Y1101004D03*
Y1096004D03*
Y1091004D03*
Y1086004D03*
Y1176004D03*
Y1171004D03*
Y1166004D03*
Y1161004D03*
Y1156004D03*
Y1151004D03*
Y1146004D03*
Y1141004D03*
Y1136004D03*
Y1196004D03*
Y1191004D03*
Y1186004D03*
Y1181004D03*
X490846Y195492D03*
Y190492D03*
Y185492D03*
Y180492D03*
Y175492D03*
Y170492D03*
Y165492D03*
Y260492D03*
Y255492D03*
Y250492D03*
Y245492D03*
Y240492D03*
Y235492D03*
Y230492D03*
Y225492D03*
Y220492D03*
Y290492D03*
Y285492D03*
Y280492D03*
Y275492D03*
Y270492D03*
Y265492D03*
Y648248D03*
Y643248D03*
Y638248D03*
Y633248D03*
Y628248D03*
Y623248D03*
Y618248D03*
Y693248D03*
Y688248D03*
Y683248D03*
Y678248D03*
Y673248D03*
Y743248D03*
Y738248D03*
Y733248D03*
Y728248D03*
Y723248D03*
Y718248D03*
Y713248D03*
Y708248D03*
Y703248D03*
Y698248D03*
Y1081004D03*
Y1076004D03*
Y1071004D03*
Y1131004D03*
Y1126004D03*
Y1101004D03*
Y1096004D03*
Y1091004D03*
Y1086004D03*
Y1176004D03*
Y1171004D03*
Y1166004D03*
Y1161004D03*
Y1156004D03*
Y1151004D03*
Y1146004D03*
Y1141004D03*
Y1136004D03*
Y1196004D03*
Y1191004D03*
Y1186004D03*
Y1181004D03*
X615059Y195492D03*
Y190492D03*
Y185492D03*
Y180492D03*
Y175492D03*
Y170492D03*
Y165492D03*
Y260492D03*
Y255492D03*
Y250492D03*
Y245492D03*
Y240492D03*
Y235492D03*
Y230492D03*
Y225492D03*
Y220492D03*
Y290492D03*
Y285492D03*
Y280492D03*
Y275492D03*
Y270492D03*
Y265492D03*
Y648248D03*
Y643248D03*
Y638248D03*
Y633248D03*
Y628248D03*
Y623248D03*
Y618248D03*
Y693248D03*
Y688248D03*
Y683248D03*
Y678248D03*
Y673248D03*
Y743248D03*
Y738248D03*
Y733248D03*
Y728248D03*
Y723248D03*
Y718248D03*
Y713248D03*
Y708248D03*
Y703248D03*
Y698248D03*
Y1081004D03*
Y1076004D03*
Y1071004D03*
Y1131004D03*
Y1126004D03*
Y1101004D03*
Y1096004D03*
Y1091004D03*
Y1086004D03*
Y1176004D03*
Y1171004D03*
Y1166004D03*
Y1161004D03*
Y1156004D03*
Y1151004D03*
Y1146004D03*
Y1141004D03*
Y1136004D03*
Y1196004D03*
Y1191004D03*
Y1186004D03*
Y1181004D03*
X739272Y195492D03*
Y190492D03*
Y185492D03*
Y180492D03*
Y175492D03*
Y170492D03*
Y165492D03*
Y260492D03*
Y255492D03*
Y250492D03*
Y245492D03*
Y240492D03*
Y235492D03*
Y230492D03*
Y225492D03*
Y220492D03*
Y290492D03*
Y285492D03*
Y280492D03*
Y275492D03*
Y270492D03*
Y265492D03*
Y648248D03*
Y643248D03*
Y638248D03*
Y633248D03*
Y628248D03*
Y623248D03*
Y618248D03*
Y693248D03*
Y688248D03*
Y683248D03*
Y678248D03*
Y673248D03*
Y743248D03*
Y738248D03*
Y733248D03*
Y728248D03*
Y723248D03*
Y718248D03*
Y713248D03*
Y708248D03*
Y703248D03*
Y698248D03*
Y1081004D03*
Y1076004D03*
Y1071004D03*
Y1131004D03*
Y1126004D03*
Y1101004D03*
Y1096004D03*
Y1091004D03*
Y1086004D03*
Y1176004D03*
Y1171004D03*
Y1166004D03*
Y1161004D03*
Y1156004D03*
Y1151004D03*
Y1146004D03*
Y1141004D03*
Y1136004D03*
Y1196004D03*
Y1191004D03*
Y1186004D03*
Y1181004D03*
X1288878Y195492D03*
Y190492D03*
Y185492D03*
Y180492D03*
Y175492D03*
Y170492D03*
Y165492D03*
Y260492D03*
Y255492D03*
Y250492D03*
Y245492D03*
Y240492D03*
Y235492D03*
Y230492D03*
Y225492D03*
Y220492D03*
Y290492D03*
Y285492D03*
Y280492D03*
Y275492D03*
Y270492D03*
Y265492D03*
Y648248D03*
Y643248D03*
Y638248D03*
Y633248D03*
Y628248D03*
Y623248D03*
Y618248D03*
Y693248D03*
Y688248D03*
Y683248D03*
Y678248D03*
Y673248D03*
Y743248D03*
Y738248D03*
Y733248D03*
Y728248D03*
Y723248D03*
Y718248D03*
Y713248D03*
Y708248D03*
Y703248D03*
Y698248D03*
Y1081004D03*
Y1076004D03*
Y1071004D03*
Y1131004D03*
Y1126004D03*
Y1101004D03*
Y1096004D03*
Y1091004D03*
Y1086004D03*
Y1176004D03*
Y1171004D03*
Y1166004D03*
Y1161004D03*
Y1156004D03*
Y1151004D03*
Y1146004D03*
Y1141004D03*
Y1136004D03*
Y1196004D03*
Y1191004D03*
Y1186004D03*
Y1181004D03*
X1413091Y195492D03*
Y190492D03*
Y185492D03*
Y180492D03*
Y175492D03*
Y170492D03*
Y165492D03*
Y260492D03*
Y255492D03*
Y250492D03*
Y245492D03*
Y240492D03*
Y235492D03*
Y230492D03*
Y225492D03*
Y220492D03*
Y290492D03*
Y285492D03*
Y280492D03*
Y275492D03*
Y270492D03*
Y265492D03*
Y648248D03*
Y643248D03*
Y638248D03*
Y633248D03*
Y628248D03*
Y623248D03*
Y618248D03*
Y693248D03*
Y688248D03*
Y683248D03*
Y678248D03*
Y673248D03*
Y743248D03*
Y738248D03*
Y733248D03*
Y728248D03*
Y723248D03*
Y718248D03*
Y713248D03*
Y708248D03*
Y703248D03*
Y698248D03*
Y1081004D03*
Y1076004D03*
Y1071004D03*
Y1131004D03*
Y1126004D03*
Y1101004D03*
Y1096004D03*
Y1091004D03*
Y1086004D03*
Y1176004D03*
Y1171004D03*
Y1166004D03*
Y1161004D03*
Y1156004D03*
Y1151004D03*
Y1146004D03*
Y1141004D03*
Y1136004D03*
Y1196004D03*
Y1191004D03*
Y1186004D03*
Y1181004D03*
X1537303Y195492D03*
Y190492D03*
Y185492D03*
Y180492D03*
Y175492D03*
Y170492D03*
Y165492D03*
Y260492D03*
Y255492D03*
Y250492D03*
Y245492D03*
Y240492D03*
Y235492D03*
Y230492D03*
Y225492D03*
Y220492D03*
Y290492D03*
Y285492D03*
Y280492D03*
Y275492D03*
Y270492D03*
Y265492D03*
Y648248D03*
Y643248D03*
Y638248D03*
Y633248D03*
Y628248D03*
Y623248D03*
Y618248D03*
Y693248D03*
Y688248D03*
Y683248D03*
Y678248D03*
Y673248D03*
Y743248D03*
Y738248D03*
Y733248D03*
Y728248D03*
Y723248D03*
Y718248D03*
Y713248D03*
Y708248D03*
Y703248D03*
Y698248D03*
Y1081004D03*
Y1076004D03*
Y1071004D03*
Y1131004D03*
Y1126004D03*
Y1101004D03*
Y1096004D03*
Y1091004D03*
Y1086004D03*
Y1176004D03*
Y1171004D03*
Y1166004D03*
Y1161004D03*
Y1156004D03*
Y1151004D03*
Y1146004D03*
Y1141004D03*
Y1136004D03*
Y1196004D03*
Y1191004D03*
Y1186004D03*
Y1181004D03*
X1661516Y195492D03*
Y190492D03*
Y185492D03*
Y180492D03*
Y175492D03*
Y170492D03*
Y165492D03*
Y260492D03*
Y255492D03*
Y250492D03*
Y245492D03*
Y240492D03*
Y235492D03*
Y230492D03*
Y225492D03*
Y220492D03*
Y290492D03*
Y285492D03*
Y280492D03*
Y275492D03*
Y270492D03*
Y265492D03*
Y648248D03*
Y643248D03*
Y638248D03*
Y633248D03*
Y628248D03*
Y623248D03*
Y618248D03*
Y693248D03*
Y688248D03*
Y683248D03*
Y678248D03*
Y673248D03*
Y743248D03*
Y738248D03*
Y733248D03*
Y728248D03*
Y723248D03*
Y718248D03*
Y713248D03*
Y708248D03*
Y703248D03*
Y698248D03*
Y1081004D03*
Y1076004D03*
Y1071004D03*
Y1131004D03*
Y1126004D03*
Y1101004D03*
Y1096004D03*
Y1091004D03*
Y1086004D03*
Y1176004D03*
Y1171004D03*
Y1166004D03*
Y1161004D03*
Y1156004D03*
Y1151004D03*
Y1146004D03*
Y1141004D03*
Y1136004D03*
Y1196004D03*
Y1191004D03*
Y1186004D03*
Y1181004D03*
X1785728Y195492D03*
Y190492D03*
Y185492D03*
Y180492D03*
Y175492D03*
Y170492D03*
Y165492D03*
Y260492D03*
Y255492D03*
Y250492D03*
Y245492D03*
Y240492D03*
Y235492D03*
Y230492D03*
Y225492D03*
Y220492D03*
Y290492D03*
Y285492D03*
Y280492D03*
Y275492D03*
Y270492D03*
Y265492D03*
Y648248D03*
Y643248D03*
Y638248D03*
Y633248D03*
Y628248D03*
Y623248D03*
Y618248D03*
Y693248D03*
Y688248D03*
Y683248D03*
Y678248D03*
Y673248D03*
Y743248D03*
Y738248D03*
Y733248D03*
Y728248D03*
Y723248D03*
Y718248D03*
Y713248D03*
Y708248D03*
Y703248D03*
Y698248D03*
Y1081004D03*
Y1076004D03*
Y1071004D03*
Y1131004D03*
Y1126004D03*
Y1101004D03*
Y1096004D03*
Y1091004D03*
Y1086004D03*
Y1176004D03*
Y1171004D03*
Y1166004D03*
Y1161004D03*
Y1156004D03*
Y1151004D03*
Y1146004D03*
Y1141004D03*
Y1136004D03*
Y1196004D03*
Y1191004D03*
Y1186004D03*
Y1181004D03*
X1909941Y195492D03*
Y190492D03*
Y185492D03*
Y180492D03*
Y175492D03*
Y170492D03*
Y165492D03*
Y260492D03*
Y255492D03*
Y250492D03*
Y245492D03*
Y240492D03*
Y235492D03*
Y230492D03*
Y225492D03*
Y220492D03*
Y290492D03*
Y285492D03*
Y280492D03*
Y275492D03*
Y270492D03*
Y265492D03*
Y648248D03*
Y643248D03*
Y638248D03*
Y633248D03*
Y628248D03*
Y623248D03*
Y618248D03*
Y693248D03*
Y688248D03*
Y683248D03*
Y678248D03*
Y673248D03*
Y743248D03*
Y738248D03*
Y733248D03*
Y728248D03*
Y723248D03*
Y718248D03*
Y713248D03*
Y708248D03*
Y703248D03*
Y698248D03*
Y1081004D03*
Y1076004D03*
Y1071004D03*
Y1131004D03*
Y1126004D03*
Y1101004D03*
Y1096004D03*
Y1091004D03*
Y1086004D03*
Y1176004D03*
Y1171004D03*
Y1166004D03*
Y1161004D03*
Y1156004D03*
Y1151004D03*
Y1146004D03*
Y1141004D03*
Y1136004D03*
Y1196004D03*
Y1191004D03*
Y1186004D03*
Y1181004D03*
G54D65*
X683341Y593826D03*
X689747D03*
G54D83*
X1181145Y274100D03*
X1183115D03*
Y264900D03*
X1181145D03*
X1185085Y274100D03*
X1187055D03*
Y264900D03*
X1185085D03*
G54D47*
X139937Y270661D03*
Y723417D03*
X147063Y1005225D03*
X140100Y1176000D03*
X213763Y593225D03*
X264149Y270661D03*
Y723417D03*
X264200Y1176000D03*
X388362Y270661D03*
Y723417D03*
X388200Y1176000D03*
X512574Y270661D03*
Y723417D03*
X512500Y1176000D03*
X636787Y270461D03*
Y723417D03*
X636800Y1176000D03*
X749000Y723417D03*
X751300Y270500D03*
X760900Y1176000D03*
X884000Y503300D03*
X884069Y536587D03*
X884143Y522805D03*
Y516205D03*
X884069Y529987D03*
X883969Y548187D03*
X884143Y509905D03*
X884069Y587087D03*
X884143Y593105D03*
Y599205D03*
X884043Y605505D03*
Y611905D03*
X869534Y1363511D03*
X1005471Y14243D03*
X1005571Y7943D03*
Y20443D03*
X1005471Y26543D03*
Y32343D03*
X1005371Y44043D03*
X1005457Y38271D03*
X1005557Y49871D03*
X1005898Y72514D03*
Y79114D03*
X1005157Y579054D03*
X1072205Y31082D03*
Y38982D03*
X1067705Y35182D03*
X1067805Y27282D03*
X1067705Y42682D03*
X1072382Y46195D03*
X1067200Y48900D03*
X1072200Y52000D03*
X1072132Y64668D03*
Y70368D03*
X1051915Y518253D03*
Y524853D03*
X1051869Y538079D03*
Y531479D03*
X1051957Y505702D03*
Y512302D03*
X1051131Y586321D03*
X1051185Y574247D03*
X1051147Y598615D03*
Y592415D03*
X1051185Y580347D03*
X1051200Y568300D03*
X1051181Y562366D03*
X1250500Y273500D03*
X1254000Y722917D03*
X1253900Y1176000D03*
X1378700Y270400D03*
X1378213Y722917D03*
X1378400Y1176000D03*
X1500900Y265600D03*
X1502425Y722917D03*
X1502300Y1176000D03*
X1628000Y270500D03*
X1626638Y722917D03*
X1626000Y1176000D03*
X1750900Y270500D03*
X1753000Y756000D03*
X1747400Y1176000D03*
X1788863Y1017225D03*
X1877400Y265200D03*
X1874807Y707280D03*
X1887000Y1170756D03*
G54D66*
X794488Y11615D03*
X885040D03*
G54D75*
X972995Y1165653D03*
X975555D03*
X978115D03*
Y1172153D03*
X972995D03*
X1325735Y65129D03*
X1328295D03*
X1325735Y71629D03*
X1330855Y65129D03*
Y71629D03*
G54D48*
X338971Y64135D03*
X345471Y66695D03*
Y64135D03*
X338971Y69255D03*
X345471D03*
X536871Y547216D03*
Y544656D03*
Y542096D03*
X543371D03*
Y547216D03*
X682452Y112770D03*
Y107650D03*
X675952D03*
Y110210D03*
Y112770D03*
X841508Y1533251D03*
Y1530691D03*
Y1528131D03*
X848008D03*
Y1533251D03*
X907950Y1525060D03*
Y1522500D03*
Y1519940D03*
X914450D03*
Y1525060D03*
X1233900Y230740D03*
Y235860D03*
X1240400D03*
Y233300D03*
Y230740D03*
X1491108Y545215D03*
Y547775D03*
Y550335D03*
X1484608D03*
Y545215D03*
G54D84*
X1265178Y171892D03*
X1267378D03*
X1265178Y174092D03*
X1267378D03*
Y624648D03*
X1265178D03*
X1267378Y626848D03*
X1265178D03*
X1267378Y1077404D03*
X1265178D03*
X1267378Y1079604D03*
X1265178D03*
X1391591Y171892D03*
X1389391D03*
X1391591Y174092D03*
X1389391D03*
X1391591Y624648D03*
X1389391D03*
X1391591Y626848D03*
X1389391D03*
X1391591Y1077404D03*
X1389391D03*
X1391591Y1079604D03*
X1389391D03*
X1515803Y171892D03*
X1513603D03*
X1515803Y174092D03*
X1513603D03*
X1515803Y624648D03*
X1513603D03*
X1515803Y626848D03*
X1513603D03*
X1515803Y1077404D03*
X1513603D03*
X1515803Y1079604D03*
X1513603D03*
X1640016Y171892D03*
X1637816D03*
X1640016Y174092D03*
X1637816D03*
X1640016Y624648D03*
X1637816D03*
X1640016Y626848D03*
X1637816D03*
X1640016Y1077404D03*
X1637816D03*
X1640016Y1079604D03*
X1637816D03*
X1764228Y171892D03*
X1762028D03*
X1764228Y174092D03*
X1762028D03*
X1739228Y624648D03*
X1737028D03*
X1739228Y626848D03*
X1737028D03*
X1764228Y1077404D03*
X1762028D03*
X1764228Y1079604D03*
X1762028D03*
X1888441Y171892D03*
X1886241D03*
X1888441Y174092D03*
X1886241D03*
X1888441Y624648D03*
X1886241D03*
X1888441Y626848D03*
X1886241D03*
X1888441Y1077404D03*
X1886241D03*
X1888441Y1079604D03*
X1886241D03*
G54D57*
X580829Y549721D03*
Y535941D03*
X560729D03*
Y549721D03*
X929950Y1522310D03*
Y1536090D03*
X950050D03*
Y1522310D03*
X1447150Y542710D03*
X1467250D03*
X1447150Y556490D03*
X1467250D03*
G54D39*
X77877Y194861D03*
X80437D03*
X82997D03*
X77877Y187461D03*
X80437D03*
X82997D03*
Y647617D03*
X80437D03*
X77877D03*
Y640217D03*
X80437D03*
X82997D03*
Y1100373D03*
X80437D03*
X77877D03*
Y1092973D03*
X80437D03*
X82997D03*
X202089Y194861D03*
X204649D03*
X207209D03*
X202089Y187461D03*
X204649D03*
X207209D03*
X207409Y638617D03*
X204849D03*
X202289D03*
Y631217D03*
X204849D03*
X207409D03*
X207209Y1100373D03*
X204649D03*
X202089D03*
Y1092973D03*
X204649D03*
X207209D03*
X326302Y194861D03*
X328862D03*
X331422D03*
X326302Y187461D03*
X328862D03*
X331422D03*
Y647617D03*
X328862D03*
X326302D03*
Y640217D03*
X328862D03*
X331422D03*
Y1100373D03*
X328862D03*
X326302D03*
Y1092973D03*
X328862D03*
X331422D03*
X450514Y194861D03*
X453074D03*
X455634D03*
X450514Y187461D03*
X453074D03*
X455634D03*
Y647617D03*
X453074D03*
X450514D03*
Y640217D03*
X453074D03*
X455634D03*
X574727Y194861D03*
X577287D03*
X579847D03*
X574727Y187461D03*
X577287D03*
X579847D03*
Y647617D03*
X577287D03*
X574727D03*
Y640217D03*
X577287D03*
X579847D03*
Y1100373D03*
X577287D03*
X574727D03*
Y1092973D03*
X577287D03*
X579847D03*
X698940Y194861D03*
X701500D03*
X698940Y187461D03*
X701500D03*
X699140Y649117D03*
Y641717D03*
X701500Y1100373D03*
X698940D03*
Y1092973D03*
X701500D03*
X704060Y194861D03*
Y187461D03*
X704260Y649117D03*
X701700D03*
Y641717D03*
X704260D03*
X704060Y1100373D03*
Y1092973D03*
X1021660Y-56732D03*
X1019100D03*
X1016540D03*
X1021660Y-49332D03*
X1019100D03*
X1016540D03*
X1006660Y-59968D03*
X1004100D03*
X1001540D03*
X1006660Y-52568D03*
X1004100D03*
X1001540D03*
X1086740Y-77432D03*
X1076960Y-63832D03*
X1074400D03*
X1071840D03*
X1076960Y-56432D03*
X1074400D03*
X1071840D03*
X1086740Y-70032D03*
X1091860Y-77432D03*
X1089300D03*
X1109922Y-72521D03*
X1107362D03*
X1104802D03*
X1109922Y-65121D03*
X1107362D03*
X1104802D03*
X1091860Y-70032D03*
X1089300D03*
G54D67*
X845670Y5709D03*
X841733D03*
X837795D03*
X833858D03*
X829921D03*
X825984D03*
X822047D03*
X818110D03*
X814173D03*
X810236D03*
X806299D03*
X802362D03*
X845670Y29725D03*
X841733D03*
X837795D03*
X833858D03*
X829921D03*
X825984D03*
X822047D03*
X818110D03*
X814173D03*
X810236D03*
X806299D03*
X802362D03*
X877166Y5709D03*
X873229D03*
X869292D03*
X865355D03*
X861418D03*
X857481D03*
X853544D03*
X849607D03*
X877166Y29725D03*
X873229D03*
X869292D03*
X865355D03*
X861418D03*
X857481D03*
X853544D03*
X849607D03*
G54D85*
X1328500Y210661D03*
Y205661D03*
Y200661D03*
X1308500D03*
Y205661D03*
Y210661D03*
X1328500Y215661D03*
X1308500D03*
X1328500Y668417D03*
Y663417D03*
Y658417D03*
Y653417D03*
X1308500D03*
Y658417D03*
Y663417D03*
Y668417D03*
X1328500Y1121173D03*
Y1116173D03*
Y1111173D03*
Y1106173D03*
X1308500D03*
Y1111173D03*
Y1116173D03*
Y1121173D03*
X1452713Y210661D03*
Y205661D03*
Y200661D03*
X1432713D03*
Y205661D03*
Y210661D03*
X1452713Y215661D03*
X1432713D03*
X1452713Y668417D03*
Y663417D03*
Y658417D03*
Y653417D03*
X1432713D03*
Y658417D03*
Y663417D03*
Y668417D03*
X1452713Y1121173D03*
Y1116173D03*
Y1111173D03*
Y1106173D03*
X1432713D03*
Y1111173D03*
Y1116173D03*
Y1121173D03*
X1556925Y200661D03*
Y205661D03*
Y210661D03*
Y215661D03*
X1571925Y670417D03*
Y665417D03*
Y660417D03*
Y655417D03*
X1551925D03*
Y660417D03*
Y665417D03*
Y670417D03*
X1572100Y1099700D03*
Y1104700D03*
Y1109700D03*
Y1114700D03*
X1576925Y210661D03*
Y205661D03*
Y200661D03*
Y215661D03*
X1592100Y1114700D03*
Y1109700D03*
Y1104700D03*
Y1099700D03*
X1701138Y210661D03*
Y205661D03*
Y200661D03*
X1681138D03*
Y205661D03*
Y210661D03*
X1701138Y215661D03*
X1681138D03*
X1701138Y668417D03*
Y663417D03*
Y658417D03*
Y653417D03*
X1681138D03*
Y658417D03*
Y663417D03*
Y668417D03*
X1701138Y1121173D03*
Y1116173D03*
Y1111173D03*
Y1106173D03*
X1681138D03*
Y1111173D03*
Y1116173D03*
Y1121173D03*
X1805350Y200661D03*
Y205661D03*
Y210661D03*
Y215661D03*
Y653417D03*
Y658417D03*
Y663417D03*
Y668417D03*
X1803350Y1106173D03*
Y1111173D03*
Y1116173D03*
Y1121173D03*
X1825350Y210661D03*
Y205661D03*
Y200661D03*
Y215661D03*
Y668417D03*
Y663417D03*
Y658417D03*
Y653417D03*
X1823350Y1121173D03*
Y1116173D03*
Y1111173D03*
Y1106173D03*
G54D76*
X1013662Y-103956D03*
X1010512D03*
X1007363D03*
X1004213D03*
X1001063D03*
X997914D03*
X994764D03*
G54D49*
X324841Y87515D03*
X327401D03*
X329961D03*
X332521D03*
X335081D03*
X337641D03*
X340201D03*
X342761D03*
X345321D03*
X347881D03*
X350441D03*
X353001D03*
Y109715D03*
X350441D03*
X347881D03*
X345321D03*
X342761D03*
X340201D03*
X337641D03*
X335081D03*
X332521D03*
X329961D03*
X327401D03*
X324841D03*
X876781Y1450061D03*
X879341D03*
X881901D03*
X884461D03*
X887021D03*
X889581D03*
X892141D03*
X894701D03*
Y1472261D03*
X892141D03*
X889581D03*
X887021D03*
X884461D03*
X881901D03*
X879341D03*
X876781D03*
X896420Y921900D03*
X898980D03*
X901540D03*
X904100D03*
X906660D03*
X909220D03*
X911780D03*
X914340D03*
X916900D03*
X919460D03*
X922020D03*
X924580D03*
Y944100D03*
X922020D03*
X919460D03*
X916900D03*
X914340D03*
X911780D03*
X909220D03*
X906660D03*
X904100D03*
X901540D03*
X898980D03*
X896420D03*
X927080Y1013600D03*
X924520D03*
X921960D03*
X919400D03*
X916840D03*
X914280D03*
X911720D03*
X909160D03*
X906600D03*
X904040D03*
X901480D03*
X898920D03*
Y991400D03*
X901480D03*
X904040D03*
X906600D03*
X909160D03*
X911720D03*
X914280D03*
X916840D03*
X919400D03*
X921960D03*
X924520D03*
X927080D03*
X897261Y1450061D03*
X899821D03*
X902381D03*
X904941D03*
Y1472261D03*
X902381D03*
X899821D03*
X897261D03*
X953420Y921900D03*
X955980D03*
X958540D03*
X961100D03*
X963660D03*
X966220D03*
X968780D03*
X971340D03*
X973900D03*
X976460D03*
X979020D03*
X981580D03*
Y944100D03*
X979020D03*
X976460D03*
X973900D03*
X971340D03*
X968780D03*
X966220D03*
X963660D03*
X961100D03*
X958540D03*
X955980D03*
X953420D03*
X948420Y992400D03*
X950980D03*
X953540D03*
X956100D03*
X958660D03*
X961220D03*
X963780D03*
X966340D03*
X968900D03*
X971460D03*
X974020D03*
X976580D03*
Y1014600D03*
X974020D03*
X971460D03*
X968900D03*
X966340D03*
X963780D03*
X961220D03*
X958660D03*
X956100D03*
X953540D03*
X950980D03*
X948420D03*
X1020540Y921400D03*
X1023100D03*
X1025660D03*
X1028220D03*
X1030780D03*
X1033340D03*
X1035900D03*
X1038460D03*
Y943600D03*
X1035900D03*
X1033340D03*
X1030780D03*
X1028220D03*
X1025660D03*
X1023100D03*
X1020540D03*
X997614Y992740D03*
X1000174D03*
X1002734D03*
X1005294D03*
X1007854D03*
X1010414D03*
X1012974D03*
X1015534D03*
X1018094D03*
X1020654D03*
X1023214D03*
X1025774D03*
Y1014940D03*
X1023214D03*
X1020654D03*
X1018094D03*
X1015534D03*
X1012974D03*
X1010414D03*
X1007854D03*
X1005294D03*
X1002734D03*
X1000174D03*
X997614D03*
X1025920Y1083900D03*
X1028480D03*
X1031040D03*
X1033600D03*
X1036160D03*
X1038720D03*
Y1106100D03*
X1036160D03*
X1033600D03*
X1031040D03*
X1028480D03*
X1025920D03*
X1073420Y1084900D03*
X1075980D03*
X1078540D03*
X1081100D03*
X1083660D03*
X1086220D03*
X1041280Y1083900D03*
X1043840D03*
X1046400D03*
X1048960D03*
X1051520D03*
X1054080D03*
X1086220Y1107100D03*
X1083660D03*
X1081100D03*
X1078540D03*
X1075980D03*
X1073420D03*
X1054080Y1106100D03*
X1051520D03*
X1048960D03*
X1046400D03*
X1043840D03*
X1041280D03*
X1088780Y1084900D03*
X1091340D03*
X1093900D03*
X1096460D03*
X1099020D03*
X1101580D03*
X1116420D03*
X1118980D03*
X1121540D03*
X1124100D03*
X1126660D03*
X1129220D03*
X1131780D03*
X1134340D03*
X1101580Y1107100D03*
X1099020D03*
X1096460D03*
X1093900D03*
X1091340D03*
X1088780D03*
X1134340D03*
X1131780D03*
X1129220D03*
X1126660D03*
X1124100D03*
X1121540D03*
X1118980D03*
X1116420D03*
X1136900Y1084900D03*
X1139460D03*
X1142020D03*
X1144580D03*
Y1107100D03*
X1142020D03*
X1139460D03*
X1136900D03*
X1323041Y96135D03*
X1325601D03*
X1328161D03*
Y118335D03*
X1325601D03*
X1323041D03*
X1330721Y96135D03*
X1333281D03*
X1335841D03*
X1338401D03*
X1340961D03*
X1343521D03*
X1346081D03*
X1348641D03*
X1351201D03*
Y118335D03*
X1348641D03*
X1346081D03*
X1343521D03*
X1340961D03*
X1338401D03*
X1335841D03*
X1333281D03*
X1330721D03*
G54D58*
X580529Y547752D03*
Y545784D03*
Y543815D03*
Y541847D03*
Y539878D03*
Y537910D03*
X561029D03*
Y539878D03*
Y541847D03*
Y543815D03*
Y545784D03*
Y547752D03*
X930250Y1524279D03*
Y1526247D03*
Y1528216D03*
Y1530184D03*
Y1532153D03*
Y1534121D03*
X949750D03*
Y1532153D03*
Y1530184D03*
Y1528216D03*
Y1526247D03*
Y1524279D03*
X1447450Y544679D03*
Y546647D03*
Y548616D03*
Y550584D03*
X1466950D03*
Y548616D03*
Y546647D03*
Y544679D03*
X1447450Y552553D03*
Y554521D03*
X1466950D03*
Y552553D03*
G54D59*
X577669Y532781D03*
X563889D03*
Y552881D03*
X577669D03*
X933110Y1519150D03*
Y1539250D03*
X946890Y1519150D03*
Y1539250D03*
X1464090Y539550D03*
X1450310D03*
Y559650D03*
X1464090D03*
G54D86*
X1392452Y573397D03*
Y579803D03*
G54D68*
X808001Y46220D03*
Y66488D03*
X803167Y631566D03*
Y651834D03*
X808000Y1203666D03*
Y1223934D03*
X1038655Y107235D03*
Y127503D03*
X1126047Y873270D03*
Y893538D03*
X1105647Y914783D03*
Y935051D03*
G54D77*
X1017695Y-85425D03*
X1029295D03*
X1040397Y-84867D03*
X1051997D03*
G54D69*
X853379Y59870D03*
X878179D03*
X1181568Y77168D03*
X1206368D03*
G54D87*
X1384950Y573397D03*
Y579803D03*
G54D78*
X1032080Y-52355D03*
X1039560D03*
Y-61355D03*
X1035820D03*
X1032080D03*
X1054593Y-57597D03*
X1062073D03*
Y-66597D03*
X1058333D03*
X1054593D03*
G54D88*
X1426950Y571600D03*
X1419450Y567725D03*
Y575475D03*
G54D79*
X1040055Y1482511D03*
X1035055D03*
X1030055D03*
X1017255D03*
X1012255D03*
X1007255D03*
X1002255D03*
X1072855D03*
X1067855D03*
X1062855D03*
X1057855D03*
X1045055D03*
X1376200Y540900D03*
X1391200D03*
X1386200D03*
X1381200D03*
G54D89*
X1500540Y528169D03*
X1502540Y533769D03*
X1498540D03*
M02*
